G04 ================== begin FILE IDENTIFICATION RECORD ==================*
G04 Layout Name:  D:/<user>/Wistron_project/16316-1/gbr-0621/16316-1.brd*
G04 Film Name:    BSMD*
G04 File Format:  Gerber RS274X*
G04 File Origin:  Cadence Allegro 16.5-S056*
G04 Origin Date:  Wed Jun 21 09:31:37 2017*
G04 *
G04 Layer:  VIA CLASS/PASTEMASK_BOTTOM*
G04 Layer:  PIN/PASTEMASK_BOTTOM*
G04 Layer:  PACKAGE GEOMETRY/PASTEMASK_BOTTOM*
G04 Layer:  DRAWING FORMAT/LAYER_PCB_STORY*
G04 Layer:  DRAWING FORMAT/LAYER_PAST_B*
G04 Layer:  BOARD GEOMETRY/PANEL_OUTLINE*
G04 *
G04 Offset:    (0.00 0.00)*
G04 Mirror:    No*
G04 Mode:      Positive*
G04 Rotation:  0*
G04 FullContactRelief:  No*
G04 UndefLineWidth:     6.00*
G04 ================== end FILE IDENTIFICATION RECORD ====================*
%FSLAX35Y35*MOIN*%
%IR0*IPPOS*OFA0.00000B0.00000*MIA0B0*SFA1.00000B1.00000*%
%AMMACRO32*
4,1,40,.011,.007,
.011,-.007,
.010939,-.007695,
.010759,-.008368,
.010464,-.009,
.010064,-.009571,
.009571,-.010064,
.009,-.010464,
.008368,-.010759,
.007695,-.010939,
.007,-.011,
-.007,-.011,
-.007695,-.010939,
-.008368,-.010759,
-.009,-.010464,
-.009571,-.010064,
-.010064,-.009571,
-.010464,-.009,
-.010759,-.008368,
-.010939,-.007695,
-.011,-.007,
-.011,.007,
-.010939,.007695,
-.010759,.008368,
-.010464,.009,
-.010064,.009571,
-.009571,.010064,
-.009,.010464,
-.008368,.010759,
-.007695,.010939,
-.007,.011,
.007,.011,
.007695,.010939,
.008368,.010759,
.009,.010464,
.009571,.010064,
.010064,.009571,
.010464,.009,
.010759,.008368,
.010939,.007695,
.011,.007,
0.0*
%
%ADD32MACRO32*%
%AMMACRO23*
4,1,40,-.017,-.013,
-.017,.013,
-.016939,.013695,
-.016759,.014368,
-.016464,.015,
-.016064,.015571,
-.015571,.016064,
-.015,.016464,
-.014368,.016759,
-.013695,.016939,
-.013,.017,
.013,.017,
.013695,.016939,
.014368,.016759,
.015,.016464,
.015571,.016064,
.016064,.015571,
.016464,.015,
.016759,.014368,
.016939,.013695,
.017,.013,
.017,-.013,
.016939,-.013695,
.016759,-.014368,
.016464,-.015,
.016064,-.015571,
.015571,-.016064,
.015,-.016464,
.014368,-.016759,
.013695,-.016939,
.013,-.017,
-.013,-.017,
-.013695,-.016939,
-.014368,-.016759,
-.015,-.016464,
-.015571,-.016064,
-.016064,-.015571,
-.016464,-.015,
-.016759,-.014368,
-.016939,-.013695,
-.017,-.013,
0.0*
%
%ADD23MACRO23*%
%AMMACRO16*
4,1,40,.013,-.017,
-.013,-.017,
-.013695,-.016939,
-.014368,-.016759,
-.015,-.016464,
-.015571,-.016064,
-.016064,-.015571,
-.016464,-.015,
-.016759,-.014368,
-.016939,-.013695,
-.017,-.013,
-.017,.013,
-.016939,.013695,
-.016759,.014368,
-.016464,.015,
-.016064,.015571,
-.015571,.016064,
-.015,.016464,
-.014368,.016759,
-.013695,.016939,
-.013,.017,
.013,.017,
.013695,.016939,
.014368,.016759,
.015,.016464,
.015571,.016064,
.016064,.015571,
.016464,.015,
.016759,.014368,
.016939,.013695,
.017,.013,
.017,-.013,
.016939,-.013695,
.016759,-.014368,
.016464,-.015,
.016064,-.015571,
.015571,-.016064,
.015,-.016464,
.014368,-.016759,
.013695,-.016939,
.013,-.017,
0.0*
%
%ADD16MACRO16*%
%AMMACRO60*
4,1,3,-.025,.0125,
0.0,-.0125,
.025,.0125,
-.025,.0125,
0.0*
%
%ADD60MACRO60*%
%ADD10C,.04*%
%AMMACRO37*
4,1,40,-.007,-.004,
-.007,.004,
-.00697,.004347,
-.006879,.004684,
-.006732,.005,
-.006532,.005286,
-.006286,.005532,
-.006,.005732,
-.005684,.005879,
-.005347,.00597,
-.005,.006,
.005,.006,
.005347,.00597,
.005684,.005879,
.006,.005732,
.006286,.005532,
.006532,.005286,
.006732,.005,
.006879,.004684,
.00697,.004347,
.007,.004,
.007,-.004,
.00697,-.004347,
.006879,-.004684,
.006732,-.005,
.006532,-.005286,
.006286,-.005532,
.006,-.005732,
.005684,-.005879,
.005347,-.00597,
.005,-.006,
-.005,-.006,
-.005347,-.00597,
-.005684,-.005879,
-.006,-.005732,
-.006286,-.005532,
-.006532,-.005286,
-.006732,-.005,
-.006879,-.004684,
-.00697,-.004347,
-.007,-.004,
0.0*
%
%ADD37MACRO37*%
%ADD11C,.024*%
%AMMACRO49*
4,1,40,-.004,.007,
.004,.007,
.004347,.00697,
.004684,.006879,
.005,.006732,
.005286,.006532,
.005532,.006286,
.005732,.006,
.005879,.005684,
.00597,.005347,
.006,.005,
.006,-.005,
.00597,-.005347,
.005879,-.005684,
.005732,-.006,
.005532,-.006286,
.005286,-.006532,
.005,-.006732,
.004684,-.006879,
.004347,-.00697,
.004,-.007,
-.004,-.007,
-.004347,-.00697,
-.004684,-.006879,
-.005,-.006732,
-.005286,-.006532,
-.005532,-.006286,
-.005732,-.006,
-.005879,-.005684,
-.00597,-.005347,
-.006,-.005,
-.006,.005,
-.00597,.005347,
-.005879,.005684,
-.005732,.006,
-.005532,.006286,
-.005286,.006532,
-.005,.006732,
-.004684,.006879,
-.004347,.00697,
-.004,.007,
0.0*
%
%ADD49MACRO49*%
%ADD45C,.028*%
%AMMACRO54*
4,1,40,.008,.014,
-.008,.014,
-.008695,.013939,
-.009368,.013759,
-.01,.013464,
-.010571,.013064,
-.011064,.012571,
-.011464,.012,
-.011759,.011368,
-.011939,.010695,
-.012,.01,
-.012,-.01,
-.011939,-.010695,
-.011759,-.011368,
-.011464,-.012,
-.011064,-.012571,
-.010571,-.013064,
-.01,-.013464,
-.009368,-.013759,
-.008695,-.013939,
-.008,-.014,
.008,-.014,
.008695,-.013939,
.009368,-.013759,
.01,-.013464,
.010571,-.013064,
.011064,-.012571,
.011464,-.012,
.011759,-.011368,
.011939,-.010695,
.012,-.01,
.012,.01,
.011939,.010695,
.011759,.011368,
.011464,.012,
.011064,.012571,
.010571,.013064,
.01,.013464,
.009368,.013759,
.008695,.013939,
.008,.014,
0.0*
%
%ADD54MACRO54*%
%AMMACRO51*
4,1,40,.0225,.007,
.022378,.008389,
.022018,.009736,
.021428,.011,
.020628,.012142,
.019642,.013128,
.0185,.013928,
.017236,.014518,
.015889,.014878,
.0145,.015,
-.0145,.015,
-.015889,.014878,
-.017236,.014518,
-.0185,.013928,
-.019642,.013128,
-.020628,.012142,
-.021428,.011,
-.022018,.009736,
-.022378,.008389,
-.0225,.007,
-.0225,-.007,
-.022378,-.008389,
-.022018,-.009736,
-.021428,-.011,
-.020628,-.012142,
-.019642,-.013128,
-.0185,-.013928,
-.017236,-.014518,
-.015889,-.014878,
-.0145,-.015,
.0145,-.015,
.015889,-.014878,
.017236,-.014518,
.0185,-.013928,
.019642,-.013128,
.020628,-.012142,
.021428,-.011,
.022018,-.009736,
.022378,-.008389,
.0225,-.007,
.0225,.007,
0.0*
%
%ADD51MACRO51*%
%AMMACRO57*
4,1,40,.007,-.0225,
.008389,-.022378,
.009736,-.022018,
.011,-.021428,
.012142,-.020628,
.013128,-.019642,
.013928,-.0185,
.014518,-.017236,
.014878,-.015889,
.015,-.0145,
.015,.0145,
.014878,.015889,
.014518,.017236,
.013928,.0185,
.013128,.019642,
.012142,.020628,
.011,.021428,
.009736,.022018,
.008389,.022378,
.007,.0225,
-.007,.0225,
-.008389,.022378,
-.009736,.022018,
-.011,.021428,
-.012142,.020628,
-.013128,.019642,
-.013928,.0185,
-.014518,.017236,
-.014878,.015889,
-.015,.0145,
-.015,-.0145,
-.014878,-.015889,
-.014518,-.017236,
-.013928,-.0185,
-.013128,-.019642,
-.012142,-.020628,
-.011,-.021428,
-.009736,-.022018,
-.008389,-.022378,
-.007,-.0225,
.007,-.0225,
0.0*
%
%ADD57MACRO57*%
%AMMACRO38*
4,1,40,.014,-.008,
.014,.008,
.013939,.008695,
.013759,.009368,
.013464,.01,
.013064,.010571,
.012571,.011064,
.012,.011464,
.011368,.011759,
.010695,.011939,
.01,.012,
-.01,.012,
-.010695,.011939,
-.011368,.011759,
-.012,.011464,
-.012571,.011064,
-.013064,.010571,
-.013464,.01,
-.013759,.009368,
-.013939,.008695,
-.014,.008,
-.014,-.008,
-.013939,-.008695,
-.013759,-.009368,
-.013464,-.01,
-.013064,-.010571,
-.012571,-.011064,
-.012,-.011464,
-.011368,-.011759,
-.010695,-.011939,
-.01,-.012,
.01,-.012,
.010695,-.011939,
.011368,-.011759,
.012,-.011464,
.012571,-.011064,
.013064,-.010571,
.013464,-.01,
.013759,-.009368,
.013939,-.008695,
.014,-.008,
0.0*
%
%ADD38MACRO38*%
%AMMACRO41*
4,1,40,.007,-.011,
-.007,-.011,
-.007695,-.010939,
-.008368,-.010759,
-.009,-.010464,
-.009571,-.010064,
-.010064,-.009571,
-.010464,-.009,
-.010759,-.008368,
-.010939,-.007695,
-.011,-.007,
-.011,.007,
-.010939,.007695,
-.010759,.008368,
-.010464,.009,
-.010064,.009571,
-.009571,.010064,
-.009,.010464,
-.008368,.010759,
-.007695,.010939,
-.007,.011,
.007,.011,
.007695,.010939,
.008368,.010759,
.009,.010464,
.009571,.010064,
.010064,.009571,
.010464,.009,
.010759,.008368,
.010939,.007695,
.011,.007,
.011,-.007,
.010939,-.007695,
.010759,-.008368,
.010464,-.009,
.010064,-.009571,
.009571,-.010064,
.009,-.010464,
.008368,-.010759,
.007695,-.010939,
.007,-.011,
0.0*
%
%ADD41MACRO41*%
%AMMACRO29*
4,1,40,-.011,-.007,
-.011,.007,
-.010939,.007695,
-.010759,.008368,
-.010464,.009,
-.010064,.009571,
-.009571,.010064,
-.009,.010464,
-.008368,.010759,
-.007695,.010939,
-.007,.011,
.007,.011,
.007695,.010939,
.008368,.010759,
.009,.010464,
.009571,.010064,
.010064,.009571,
.010464,.009,
.010759,.008368,
.010939,.007695,
.011,.007,
.011,-.007,
.010939,-.007695,
.010759,-.008368,
.010464,-.009,
.010064,-.009571,
.009571,-.010064,
.009,-.010464,
.008368,-.010759,
.007695,-.010939,
.007,-.011,
-.007,-.011,
-.007695,-.010939,
-.008368,-.010759,
-.009,-.010464,
-.009571,-.010064,
-.010064,-.009571,
-.010464,-.009,
-.010759,-.008368,
-.010939,-.007695,
-.011,-.007,
0.0*
%
%ADD29MACRO29*%
%AMMACRO13*
4,1,40,-.012,-.008,
-.012,.008,
-.011939,.008695,
-.011759,.009368,
-.011464,.01,
-.011064,.010571,
-.010571,.011064,
-.01,.011464,
-.009368,.011759,
-.008695,.011939,
-.008,.012,
.008,.012,
.008695,.011939,
.009368,.011759,
.01,.011464,
.010571,.011064,
.011064,.010571,
.011464,.01,
.011759,.009368,
.011939,.008695,
.012,.008,
.012,-.008,
.011939,-.008695,
.011759,-.009368,
.011464,-.01,
.011064,-.010571,
.010571,-.011064,
.01,-.011464,
.009368,-.011759,
.008695,-.011939,
.008,-.012,
-.008,-.012,
-.008695,-.011939,
-.009368,-.011759,
-.01,-.011464,
-.010571,-.011064,
-.011064,-.010571,
-.011464,-.01,
-.011759,-.009368,
-.011939,-.008695,
-.012,-.008,
0.0*
%
%ADD13MACRO13*%
%AMMACRO34*
4,1,40,-.008,.012,
.008,.012,
.008695,.011939,
.009368,.011759,
.01,.011464,
.010571,.011064,
.011064,.010571,
.011464,.01,
.011759,.009368,
.011939,.008695,
.012,.008,
.012,-.008,
.011939,-.008695,
.011759,-.009368,
.011464,-.01,
.011064,-.010571,
.010571,-.011064,
.01,-.011464,
.009368,-.011759,
.008695,-.011939,
.008,-.012,
-.008,-.012,
-.008695,-.011939,
-.009368,-.011759,
-.01,-.011464,
-.010571,-.011064,
-.011064,-.010571,
-.011464,-.01,
-.011759,-.009368,
-.011939,-.008695,
-.012,-.008,
-.012,.008,
-.011939,.008695,
-.011759,.009368,
-.011464,.01,
-.011064,.010571,
-.010571,.011064,
-.01,.011464,
-.009368,.011759,
-.008695,.011939,
-.008,.012,
0.0*
%
%ADD34MACRO34*%
%AMMACRO26*
4,1,40,-.013,.017,
.013,.017,
.013695,.016939,
.014368,.016759,
.015,.016464,
.015571,.016064,
.016064,.015571,
.016464,.015,
.016759,.014368,
.016939,.013695,
.017,.013,
.017,-.013,
.016939,-.013695,
.016759,-.014368,
.016464,-.015,
.016064,-.015571,
.015571,-.016064,
.015,-.016464,
.014368,-.016759,
.013695,-.016939,
.013,-.017,
-.013,-.017,
-.013695,-.016939,
-.014368,-.016759,
-.015,-.016464,
-.015571,-.016064,
-.016064,-.015571,
-.016464,-.015,
-.016759,-.014368,
-.016939,-.013695,
-.017,-.013,
-.017,.013,
-.016939,.013695,
-.016759,.014368,
-.016464,.015,
-.016064,.015571,
-.015571,.016064,
-.015,.016464,
-.014368,.016759,
-.013695,.016939,
-.013,.017,
0.0*
%
%ADD26MACRO26*%
%AMMACRO20*
4,1,40,.017,.013,
.017,-.013,
.016939,-.013695,
.016759,-.014368,
.016464,-.015,
.016064,-.015571,
.015571,-.016064,
.015,-.016464,
.014368,-.016759,
.013695,-.016939,
.013,-.017,
-.013,-.017,
-.013695,-.016939,
-.014368,-.016759,
-.015,-.016464,
-.015571,-.016064,
-.016064,-.015571,
-.016464,-.015,
-.016759,-.014368,
-.016939,-.013695,
-.017,-.013,
-.017,.013,
-.016939,.013695,
-.016759,.014368,
-.016464,.015,
-.016064,.015571,
-.015571,.016064,
-.015,.016464,
-.014368,.016759,
-.013695,.016939,
-.013,.017,
.013,.017,
.013695,.016939,
.014368,.016759,
.015,.016464,
.015571,.016064,
.016064,.015571,
.016464,.015,
.016759,.014368,
.016939,.013695,
.017,.013,
0.0*
%
%ADD20MACRO20*%
%AMMACRO42*
4,1,40,.007,-.011,
-.007,-.011,
-.007695,-.010939,
-.008368,-.010759,
-.009,-.010464,
-.009571,-.010064,
-.010064,-.009571,
-.010464,-.009,
-.010759,-.008368,
-.010939,-.007695,
-.011,-.007,
-.011,.007,
-.010939,.007695,
-.010759,.008368,
-.010464,.009,
-.010064,.009571,
-.009571,.010064,
-.009,.010464,
-.008368,.010759,
-.007695,.010939,
-.007,.011,
.007,.011,
.007695,.010939,
.008368,.010759,
.009,.010464,
.009571,.010064,
.010064,.009571,
.010464,.009,
.010759,.008368,
.010939,.007695,
.011,.007,
.011,-.007,
.010939,-.007695,
.010759,-.008368,
.010464,-.009,
.010064,-.009571,
.009571,-.010064,
.009,-.010464,
.008368,-.010759,
.007695,-.010939,
.007,-.011,
0.0*
%
%ADD42MACRO42*%
%AMMACRO30*
4,1,40,-.011,-.007,
-.011,.007,
-.010939,.007695,
-.010759,.008368,
-.010464,.009,
-.010064,.009571,
-.009571,.010064,
-.009,.010464,
-.008368,.010759,
-.007695,.010939,
-.007,.011,
.007,.011,
.007695,.010939,
.008368,.010759,
.009,.010464,
.009571,.010064,
.010064,.009571,
.010464,.009,
.010759,.008368,
.010939,.007695,
.011,.007,
.011,-.007,
.010939,-.007695,
.010759,-.008368,
.010464,-.009,
.010064,-.009571,
.009571,-.010064,
.009,-.010464,
.008368,-.010759,
.007695,-.010939,
.007,-.011,
-.007,-.011,
-.007695,-.010939,
-.008368,-.010759,
-.009,-.010464,
-.009571,-.010064,
-.010064,-.009571,
-.010464,-.009,
-.010759,-.008368,
-.010939,-.007695,
-.011,-.007,
0.0*
%
%ADD30MACRO30*%
%AMMACRO12*
4,1,40,-.012,-.008,
-.012,.008,
-.011939,.008695,
-.011759,.009368,
-.011464,.01,
-.011064,.010571,
-.010571,.011064,
-.01,.011464,
-.009368,.011759,
-.008695,.011939,
-.008,.012,
.008,.012,
.008695,.011939,
.009368,.011759,
.01,.011464,
.010571,.011064,
.011064,.010571,
.011464,.01,
.011759,.009368,
.011939,.008695,
.012,.008,
.012,-.008,
.011939,-.008695,
.011759,-.009368,
.011464,-.01,
.011064,-.010571,
.010571,-.011064,
.01,-.011464,
.009368,-.011759,
.008695,-.011939,
.008,-.012,
-.008,-.012,
-.008695,-.011939,
-.009368,-.011759,
-.01,-.011464,
-.010571,-.011064,
-.011064,-.010571,
-.011464,-.01,
-.011759,-.009368,
-.011939,-.008695,
-.012,-.008,
0.0*
%
%ADD12MACRO12*%
%AMMACRO33*
4,1,40,-.008,.012,
.008,.012,
.008695,.011939,
.009368,.011759,
.01,.011464,
.010571,.011064,
.011064,.010571,
.011464,.01,
.011759,.009368,
.011939,.008695,
.012,.008,
.012,-.008,
.011939,-.008695,
.011759,-.009368,
.011464,-.01,
.011064,-.010571,
.010571,-.011064,
.01,-.011464,
.009368,-.011759,
.008695,-.011939,
.008,-.012,
-.008,-.012,
-.008695,-.011939,
-.009368,-.011759,
-.01,-.011464,
-.010571,-.011064,
-.011064,-.010571,
-.011464,-.01,
-.011759,-.009368,
-.011939,-.008695,
-.012,-.008,
-.012,.008,
-.011939,.008695,
-.011759,.009368,
-.011464,.01,
-.011064,.010571,
-.010571,.011064,
-.01,.011464,
-.009368,.011759,
-.008695,.011939,
-.008,.012,
0.0*
%
%ADD33MACRO33*%
%AMMACRO27*
4,1,40,-.013,.017,
.013,.017,
.013695,.016939,
.014368,.016759,
.015,.016464,
.015571,.016064,
.016064,.015571,
.016464,.015,
.016759,.014368,
.016939,.013695,
.017,.013,
.017,-.013,
.016939,-.013695,
.016759,-.014368,
.016464,-.015,
.016064,-.015571,
.015571,-.016064,
.015,-.016464,
.014368,-.016759,
.013695,-.016939,
.013,-.017,
-.013,-.017,
-.013695,-.016939,
-.014368,-.016759,
-.015,-.016464,
-.015571,-.016064,
-.016064,-.015571,
-.016464,-.015,
-.016759,-.014368,
-.016939,-.013695,
-.017,-.013,
-.017,.013,
-.016939,.013695,
-.016759,.014368,
-.016464,.015,
-.016064,.015571,
-.015571,.016064,
-.015,.016464,
-.014368,.016759,
-.013695,.016939,
-.013,.017,
0.0*
%
%ADD27MACRO27*%
%AMMACRO21*
4,1,40,.017,.013,
.017,-.013,
.016939,-.013695,
.016759,-.014368,
.016464,-.015,
.016064,-.015571,
.015571,-.016064,
.015,-.016464,
.014368,-.016759,
.013695,-.016939,
.013,-.017,
-.013,-.017,
-.013695,-.016939,
-.014368,-.016759,
-.015,-.016464,
-.015571,-.016064,
-.016064,-.015571,
-.016464,-.015,
-.016759,-.014368,
-.016939,-.013695,
-.017,-.013,
-.017,.013,
-.016939,.013695,
-.016759,.014368,
-.016464,.015,
-.016064,.015571,
-.015571,.016064,
-.015,.016464,
-.014368,.016759,
-.013695,.016939,
-.013,.017,
.013,.017,
.013695,.016939,
.014368,.016759,
.015,.016464,
.015571,.016064,
.016064,.015571,
.016464,.015,
.016759,.014368,
.016939,.013695,
.017,.013,
0.0*
%
%ADD21MACRO21*%
%ADD63R,.022X.04*%
%ADD61R,.06X.012*%
%AMMACRO59*
4,1,3,0.0,.0125,
-.025,-.0125,
.025,-.0125,
0.0,.0125,
0.0*
%
%ADD59MACRO59*%
%ADD46R,.023X.04*%
%ADD35R,.012X.06*%
%ADD47R,.016X.032*%
%ADD17R,.05X.08*%
%AMMACRO48*
4,1,40,.007,.004,
.007,-.004,
.00697,-.004347,
.006879,-.004684,
.006732,-.005,
.006532,-.005286,
.006286,-.005532,
.006,-.005732,
.005684,-.005879,
.005347,-.00597,
.005,-.006,
-.005,-.006,
-.005347,-.00597,
-.005684,-.005879,
-.006,-.005732,
-.006286,-.005532,
-.006532,-.005286,
-.006732,-.005,
-.006879,-.004684,
-.00697,-.004347,
-.007,-.004,
-.007,.004,
-.00697,.004347,
-.006879,.004684,
-.006732,.005,
-.006532,.005286,
-.006286,.005532,
-.006,.005732,
-.005684,.005879,
-.005347,.00597,
-.005,.006,
.005,.006,
.005347,.00597,
.005684,.005879,
.006,.005732,
.006286,.005532,
.006532,.005286,
.006732,.005,
.006879,.004684,
.00697,.004347,
.007,.004,
0.0*
%
%ADD48MACRO48*%
%AMMACRO36*
4,1,40,.004,-.007,
-.004,-.007,
-.004347,-.00697,
-.004684,-.006879,
-.005,-.006732,
-.005286,-.006532,
-.005532,-.006286,
-.005732,-.006,
-.005879,-.005684,
-.00597,-.005347,
-.006,-.005,
-.006,.005,
-.00597,.005347,
-.005879,.005684,
-.005732,.006,
-.005532,.006286,
-.005286,.006532,
-.005,.006732,
-.004684,.006879,
-.004347,.00697,
-.004,.007,
.004,.007,
.004347,.00697,
.004684,.006879,
.005,.006732,
.005286,.006532,
.005532,.006286,
.005732,.006,
.005879,.005684,
.00597,.005347,
.006,.005,
.006,-.005,
.00597,-.005347,
.005879,-.005684,
.005732,-.006,
.005532,-.006286,
.005286,-.006532,
.005,-.006732,
.004684,-.006879,
.004347,-.00697,
.004,-.007,
0.0*
%
%ADD36MACRO36*%
%ADD58R,.05X.065*%
%ADD28R,.065X.05*%
%ADD62R,.065X.025*%
%ADD55R,.048X.016*%
%ADD53R,.025X.065*%
%ADD14R,.045X.055*%
%ADD40R,.055X.045*%
%AMMACRO56*
4,1,40,-.007,.0225,
-.008389,.022378,
-.009736,.022018,
-.011,.021428,
-.012142,.020628,
-.013128,.019642,
-.013928,.0185,
-.014518,.017236,
-.014878,.015889,
-.015,.0145,
-.015,-.0145,
-.014878,-.015889,
-.014518,-.017236,
-.013928,-.0185,
-.013128,-.019642,
-.012142,-.020628,
-.011,-.021428,
-.009736,-.022018,
-.008389,-.022378,
-.007,-.0225,
.007,-.0225,
.008389,-.022378,
.009736,-.022018,
.011,-.021428,
.012142,-.020628,
.013128,-.019642,
.013928,-.0185,
.014518,-.017236,
.014878,-.015889,
.015,-.0145,
.015,.0145,
.014878,.015889,
.014518,.017236,
.013928,.0185,
.013128,.019642,
.012142,.020628,
.011,.021428,
.009736,.022018,
.008389,.022378,
.007,.0225,
-.007,.0225,
0.0*
%
%ADD56MACRO56*%
%AMMACRO52*
4,1,40,-.0225,-.007,
-.022378,-.008389,
-.022018,-.009736,
-.021428,-.011,
-.020628,-.012142,
-.019642,-.013128,
-.0185,-.013928,
-.017236,-.014518,
-.015889,-.014878,
-.0145,-.015,
.0145,-.015,
.015889,-.014878,
.017236,-.014518,
.0185,-.013928,
.019642,-.013128,
.020628,-.012142,
.021428,-.011,
.022018,-.009736,
.022378,-.008389,
.0225,-.007,
.0225,.007,
.022378,.008389,
.022018,.009736,
.021428,.011,
.020628,.012142,
.019642,.013128,
.0185,.013928,
.017236,.014518,
.015889,.014878,
.0145,.015,
-.0145,.015,
-.015889,.014878,
-.017236,.014518,
-.0185,.013928,
-.019642,.013128,
-.020628,.012142,
-.021428,.011,
-.022018,.009736,
-.022378,.008389,
-.0225,.007,
-.0225,-.007,
0.0*
%
%ADD52MACRO52*%
%AMMACRO50*
4,1,40,-.008,-.014,
.008,-.014,
.008695,-.013939,
.009368,-.013759,
.01,-.013464,
.010571,-.013064,
.011064,-.012571,
.011464,-.012,
.011759,-.011368,
.011939,-.010695,
.012,-.01,
.012,.01,
.011939,.010695,
.011759,.011368,
.011464,.012,
.011064,.012571,
.010571,.013064,
.01,.013464,
.009368,.013759,
.008695,.013939,
.008,.014,
-.008,.014,
-.008695,.013939,
-.009368,.013759,
-.01,.013464,
-.010571,.013064,
-.011064,.012571,
-.011464,.012,
-.011759,.011368,
-.011939,.010695,
-.012,.01,
-.012,-.01,
-.011939,-.010695,
-.011759,-.011368,
-.011464,-.012,
-.011064,-.012571,
-.010571,-.013064,
-.01,-.013464,
-.009368,-.013759,
-.008695,-.013939,
-.008,-.014,
0.0*
%
%ADD50MACRO50*%
%AMMACRO39*
4,1,40,-.014,.008,
-.014,-.008,
-.013939,-.008695,
-.013759,-.009368,
-.013464,-.01,
-.013064,-.010571,
-.012571,-.011064,
-.012,-.011464,
-.011368,-.011759,
-.010695,-.011939,
-.01,-.012,
.01,-.012,
.010695,-.011939,
.011368,-.011759,
.012,-.011464,
.012571,-.011064,
.013064,-.010571,
.013464,-.01,
.013759,-.009368,
.013939,-.008695,
.014,-.008,
.014,.008,
.013939,.008695,
.013759,.009368,
.013464,.01,
.013064,.010571,
.012571,.011064,
.012,.011464,
.011368,.011759,
.010695,.011939,
.01,.012,
-.01,.012,
-.010695,.011939,
-.011368,.011759,
-.012,.011464,
-.012571,.011064,
-.013064,.010571,
-.013464,.01,
-.013759,.009368,
-.013939,.008695,
-.014,.008,
0.0*
%
%ADD39MACRO39*%
%AMMACRO43*
4,1,40,-.007,.011,
.007,.011,
.007695,.010939,
.008368,.010759,
.009,.010464,
.009571,.010064,
.010064,.009571,
.010464,.009,
.010759,.008368,
.010939,.007695,
.011,.007,
.011,-.007,
.010939,-.007695,
.010759,-.008368,
.010464,-.009,
.010064,-.009571,
.009571,-.010064,
.009,-.010464,
.008368,-.010759,
.007695,-.010939,
.007,-.011,
-.007,-.011,
-.007695,-.010939,
-.008368,-.010759,
-.009,-.010464,
-.009571,-.010064,
-.010064,-.009571,
-.010464,-.009,
-.010759,-.008368,
-.010939,-.007695,
-.011,-.007,
-.011,.007,
-.010939,.007695,
-.010759,.008368,
-.010464,.009,
-.010064,.009571,
-.009571,.010064,
-.009,.010464,
-.008368,.010759,
-.007695,.010939,
-.007,.011,
0.0*
%
%ADD43MACRO43*%
%AMMACRO25*
4,1,40,.008,-.012,
-.008,-.012,
-.008695,-.011939,
-.009368,-.011759,
-.01,-.011464,
-.010571,-.011064,
-.011064,-.010571,
-.011464,-.01,
-.011759,-.009368,
-.011939,-.008695,
-.012,-.008,
-.012,.008,
-.011939,.008695,
-.011759,.009368,
-.011464,.01,
-.011064,.010571,
-.010571,.011064,
-.01,.011464,
-.009368,.011759,
-.008695,.011939,
-.008,.012,
.008,.012,
.008695,.011939,
.009368,.011759,
.01,.011464,
.010571,.011064,
.011064,.010571,
.011464,.01,
.011759,.009368,
.011939,.008695,
.012,.008,
.012,-.008,
.011939,-.008695,
.011759,-.009368,
.011464,-.01,
.011064,-.010571,
.010571,-.011064,
.01,-.011464,
.009368,-.011759,
.008695,-.011939,
.008,-.012,
0.0*
%
%ADD25MACRO25*%
%AMMACRO19*
4,1,40,.012,.008,
.012,-.008,
.011939,-.008695,
.011759,-.009368,
.011464,-.01,
.011064,-.010571,
.010571,-.011064,
.01,-.011464,
.009368,-.011759,
.008695,-.011939,
.008,-.012,
-.008,-.012,
-.008695,-.011939,
-.009368,-.011759,
-.01,-.011464,
-.010571,-.011064,
-.011064,-.010571,
-.011464,-.01,
-.011759,-.009368,
-.011939,-.008695,
-.012,-.008,
-.012,.008,
-.011939,.008695,
-.011759,.009368,
-.011464,.01,
-.011064,.010571,
-.010571,.011064,
-.01,.011464,
-.009368,.011759,
-.008695,.011939,
-.008,.012,
.008,.012,
.008695,.011939,
.009368,.011759,
.01,.011464,
.010571,.011064,
.011064,.010571,
.011464,.01,
.011759,.009368,
.011939,.008695,
.012,.008,
0.0*
%
%ADD19MACRO19*%
%AMMACRO31*
4,1,40,.011,.007,
.011,-.007,
.010939,-.007695,
.010759,-.008368,
.010464,-.009,
.010064,-.009571,
.009571,-.010064,
.009,-.010464,
.008368,-.010759,
.007695,-.010939,
.007,-.011,
-.007,-.011,
-.007695,-.010939,
-.008368,-.010759,
-.009,-.010464,
-.009571,-.010064,
-.010064,-.009571,
-.010464,-.009,
-.010759,-.008368,
-.010939,-.007695,
-.011,-.007,
-.011,.007,
-.010939,.007695,
-.010759,.008368,
-.010464,.009,
-.010064,.009571,
-.009571,.010064,
-.009,.010464,
-.008368,.010759,
-.007695,.010939,
-.007,.011,
.007,.011,
.007695,.010939,
.008368,.010759,
.009,.010464,
.009571,.010064,
.010064,.009571,
.010464,.009,
.010759,.008368,
.010939,.007695,
.011,.007,
0.0*
%
%ADD31MACRO31*%
%AMMACRO22*
4,1,40,-.017,-.013,
-.017,.013,
-.016939,.013695,
-.016759,.014368,
-.016464,.015,
-.016064,.015571,
-.015571,.016064,
-.015,.016464,
-.014368,.016759,
-.013695,.016939,
-.013,.017,
.013,.017,
.013695,.016939,
.014368,.016759,
.015,.016464,
.015571,.016064,
.016064,.015571,
.016464,.015,
.016759,.014368,
.016939,.013695,
.017,.013,
.017,-.013,
.016939,-.013695,
.016759,-.014368,
.016464,-.015,
.016064,-.015571,
.015571,-.016064,
.015,-.016464,
.014368,-.016759,
.013695,-.016939,
.013,-.017,
-.013,-.017,
-.013695,-.016939,
-.014368,-.016759,
-.015,-.016464,
-.015571,-.016064,
-.016064,-.015571,
-.016464,-.015,
-.016759,-.014368,
-.016939,-.013695,
-.017,-.013,
0.0*
%
%ADD22MACRO22*%
%AMMACRO15*
4,1,40,.013,-.017,
-.013,-.017,
-.013695,-.016939,
-.014368,-.016759,
-.015,-.016464,
-.015571,-.016064,
-.016064,-.015571,
-.016464,-.015,
-.016759,-.014368,
-.016939,-.013695,
-.017,-.013,
-.017,.013,
-.016939,.013695,
-.016759,.014368,
-.016464,.015,
-.016064,.015571,
-.015571,.016064,
-.015,.016464,
-.014368,.016759,
-.013695,.016939,
-.013,.017,
.013,.017,
.013695,.016939,
.014368,.016759,
.015,.016464,
.015571,.016064,
.016064,.015571,
.016464,.015,
.016759,.014368,
.016939,.013695,
.017,.013,
.017,-.013,
.016939,-.013695,
.016759,-.014368,
.016464,-.015,
.016064,-.015571,
.015571,-.016064,
.015,-.016464,
.014368,-.016759,
.013695,-.016939,
.013,-.017,
0.0*
%
%ADD15MACRO15*%
%AMMACRO44*
4,1,40,-.007,.011,
.007,.011,
.007695,.010939,
.008368,.010759,
.009,.010464,
.009571,.010064,
.010064,.009571,
.010464,.009,
.010759,.008368,
.010939,.007695,
.011,.007,
.011,-.007,
.010939,-.007695,
.010759,-.008368,
.010464,-.009,
.010064,-.009571,
.009571,-.010064,
.009,-.010464,
.008368,-.010759,
.007695,-.010939,
.007,-.011,
-.007,-.011,
-.007695,-.010939,
-.008368,-.010759,
-.009,-.010464,
-.009571,-.010064,
-.010064,-.009571,
-.010464,-.009,
-.010759,-.008368,
-.010939,-.007695,
-.011,-.007,
-.011,.007,
-.010939,.007695,
-.010759,.008368,
-.010464,.009,
-.010064,.009571,
-.009571,.010064,
-.009,.010464,
-.008368,.010759,
-.007695,.010939,
-.007,.011,
0.0*
%
%ADD44MACRO44*%
%AMMACRO24*
4,1,40,.008,-.012,
-.008,-.012,
-.008695,-.011939,
-.009368,-.011759,
-.01,-.011464,
-.010571,-.011064,
-.011064,-.010571,
-.011464,-.01,
-.011759,-.009368,
-.011939,-.008695,
-.012,-.008,
-.012,.008,
-.011939,.008695,
-.011759,.009368,
-.011464,.01,
-.011064,.010571,
-.010571,.011064,
-.01,.011464,
-.009368,.011759,
-.008695,.011939,
-.008,.012,
.008,.012,
.008695,.011939,
.009368,.011759,
.01,.011464,
.010571,.011064,
.011064,.010571,
.011464,.01,
.011759,.009368,
.011939,.008695,
.012,.008,
.012,-.008,
.011939,-.008695,
.011759,-.009368,
.011464,-.01,
.011064,-.010571,
.010571,-.011064,
.01,-.011464,
.009368,-.011759,
.008695,-.011939,
.008,-.012,
0.0*
%
%ADD24MACRO24*%
%AMMACRO18*
4,1,40,.012,.008,
.012,-.008,
.011939,-.008695,
.011759,-.009368,
.011464,-.01,
.011064,-.010571,
.010571,-.011064,
.01,-.011464,
.009368,-.011759,
.008695,-.011939,
.008,-.012,
-.008,-.012,
-.008695,-.011939,
-.009368,-.011759,
-.01,-.011464,
-.010571,-.011064,
-.011064,-.010571,
-.011464,-.01,
-.011759,-.009368,
-.011939,-.008695,
-.012,-.008,
-.012,.008,
-.011939,.008695,
-.011759,.009368,
-.011464,.01,
-.011064,.010571,
-.010571,.011064,
-.01,.011464,
-.009368,.011759,
-.008695,.011939,
-.008,.012,
.008,.012,
.008695,.011939,
.009368,.011759,
.01,.011464,
.010571,.011064,
.011064,.010571,
.011464,.01,
.011759,.009368,
.011939,.008695,
.012,.008,
0.0*
%
%ADD18MACRO18*%
%ADD64C,.02*%
%ADD65C,.006*%
G75*
%LPD*%
G75*
G36*
G01X169038Y469636D02*
X155038D01*
Y461636D01*
X169038D01*
Y469636D01*
G37*
G36*
G01X164538Y447136D02*
X159538D01*
Y439136D01*
X164538D01*
Y447136D01*
G37*
G54D10*
X37700Y64400D03*
X86150Y441700D03*
X737400Y485700D03*
G54D20*
X254300Y363700D03*
X300500Y138700D03*
X301000Y223200D03*
X300500Y180700D03*
X362810Y249340D03*
X362868Y277487D03*
X362677Y305262D03*
X581500Y459200D03*
X676531Y379833D03*
X788107Y122593D03*
G54D11*
X34567Y205090D03*
X128611Y331774D03*
X121506Y349295D03*
X129133Y339988D03*
X114258Y351996D03*
X186054Y105503D03*
X170652Y119800D03*
X177400Y149700D03*
X140561Y420016D03*
X140820Y436738D03*
X140712Y444036D03*
X204818Y107083D03*
X238000Y149500D03*
X248746Y140710D03*
X246764Y199671D03*
X237682Y343985D03*
X259132Y405962D03*
X226076Y407980D03*
X226376Y419280D03*
X250400Y407800D03*
X237276Y408080D03*
X237576Y419380D03*
X248698Y372535D03*
X307243Y156439D03*
X270486Y130871D03*
X320000Y180000D03*
X316500Y228500D03*
X316263Y211751D03*
X275519Y213859D03*
X323700Y284500D03*
X309300Y283300D03*
X296000Y287000D03*
X276070Y401100D03*
X321467Y383273D03*
X298152Y389992D03*
X269742Y380801D03*
X266050Y385047D03*
X344484Y265072D03*
X343314Y272604D03*
X383677Y252037D03*
X379700Y279906D03*
X385803Y260151D03*
X371160Y314500D03*
X386159Y327300D03*
X335133Y412340D03*
X407484Y262952D03*
X437233Y263915D03*
X391839Y263634D03*
X389709Y245772D03*
X413115Y323215D03*
X425737Y325715D03*
X427165Y316929D03*
X435039D03*
X442913Y320866D03*
X431203Y326380D03*
X401700Y340950D03*
X392453Y331635D03*
X496828Y199110D03*
X505776Y198689D03*
X484392Y298681D03*
X477955Y301006D03*
X490158Y309055D03*
X500300Y328154D03*
X479600Y310300D03*
X501227Y354336D03*
X460484Y350953D03*
X491445Y342700D03*
X474210Y316992D03*
X462663Y323248D03*
X475834Y331163D03*
X481856Y352656D03*
X468257Y323578D03*
X498032Y312992D03*
X473265Y322929D03*
X454724Y301181D03*
X495050Y373662D03*
X506684Y455873D03*
X529512Y352016D03*
X572204Y407700D03*
X570669Y465918D03*
X532050Y476200D03*
X550100Y479850D03*
X569400Y483400D03*
X569402Y472058D03*
X561657Y461261D03*
X540140Y489830D03*
X633803Y27749D03*
X629500Y118500D03*
X599000Y236500D03*
X630500Y212900D03*
X631600Y271000D03*
X603000Y279000D03*
X611606Y322456D03*
X623969Y319984D03*
X605148Y440842D03*
X587250Y463750D03*
X577390Y453170D03*
X621308Y468700D03*
X633850Y452930D03*
X609768Y487900D03*
X652587Y21500D03*
X639426Y49015D03*
X659850Y42534D03*
X639900Y27100D03*
X646000Y62259D03*
X661644Y164498D03*
X636630Y154650D03*
X645729Y161603D03*
X657700Y139700D03*
X657570Y146235D03*
X663800Y148100D03*
X680425Y205984D03*
X656427Y226217D03*
X638361Y212930D03*
X673100Y238300D03*
X652000Y220500D03*
X668153Y210095D03*
X650904Y226864D03*
X684696Y236469D03*
X695253Y214735D03*
X689783Y215075D03*
X686982Y262854D03*
X678720Y288330D03*
X686912Y268500D03*
X653707Y342389D03*
X667400Y384700D03*
X662029Y384727D03*
X657031Y384900D03*
X680700Y373763D03*
X684017Y389383D03*
X650530Y379699D03*
X668800Y478000D03*
X668300Y464300D03*
X701900Y106000D03*
X712399Y160987D03*
X732579Y152616D03*
X715490Y131490D03*
X749533Y160800D03*
X749500Y145050D03*
X750000Y141000D03*
X748000Y167000D03*
X703290Y205505D03*
X716096Y272396D03*
X700600Y256539D03*
X711401Y477794D03*
X804300Y111300D03*
X785050Y79670D03*
X771371Y98500D03*
X766694Y86024D03*
X767200Y113600D03*
X800000Y145240D03*
X793378Y145309D03*
X785756Y145353D03*
X805200Y170300D03*
X804600Y130300D03*
X773100Y132000D03*
X765900Y119700D03*
X790050Y178350D03*
X782850D03*
X795450Y178550D03*
X800500Y232750D03*
G54D21*
X254300Y369300D03*
X300500Y144300D03*
X301000Y228800D03*
X300500Y186300D03*
X362810Y254940D03*
X362868Y283087D03*
X362677Y310862D03*
X581500Y464800D03*
X676531Y385433D03*
X788107Y128193D03*
G54D12*
X149858Y418270D03*
X261712Y59618D03*
X619226Y234952D03*
X581700Y449500D03*
X660145Y23414D03*
X667177Y135318D03*
X667118Y141825D03*
X698089Y169842D03*
X684200Y128700D03*
X676582Y128735D03*
X641123Y144911D03*
X641150Y134900D03*
X641100Y148800D03*
X671092Y195715D03*
X663412Y195705D03*
X654400Y238400D03*
X684512Y480221D03*
X704988Y145327D03*
X705610Y169842D03*
X726055Y195527D03*
X721304Y329638D03*
G54D30*
X287500Y286300D03*
X358298Y250444D03*
X358342Y278587D03*
X358214Y306662D03*
X409100Y340600D03*
X421500Y341100D03*
X440740Y341244D03*
X435200Y330600D03*
X427500Y330700D03*
X421500Y330800D03*
X396000Y340700D03*
X467900Y350800D03*
X474577Y339465D03*
X496100Y351900D03*
X497206Y341831D03*
X464000Y340800D03*
X460000D03*
X451300Y340900D03*
X491445Y346958D03*
X477400Y350900D03*
X468000Y340800D03*
X486873Y346956D03*
X472000Y350800D03*
X482618Y339442D03*
X513517Y341846D03*
X521522D03*
X517517D03*
X518500Y352300D03*
X522500D03*
X549400Y485990D03*
X631500Y105300D03*
X632300Y154700D03*
X644710Y22867D03*
X637003Y62309D03*
X689468Y246705D03*
X691887Y264477D03*
X657031Y376683D03*
X666031D03*
X661531D03*
X698541Y199189D03*
X785350Y91800D03*
X781000D03*
X802696Y137400D03*
X786500D03*
X790500D03*
X796110Y182900D03*
X792000Y229300D03*
G54D22*
X262600Y416700D03*
X301000Y164800D03*
X300500Y204800D03*
Y247300D03*
X362868Y269041D03*
X362689Y297141D03*
X631781Y134308D03*
X639120Y457930D03*
X776500Y114300D03*
X790000Y98300D03*
X776500D03*
G54D31*
X283000Y286300D03*
X316786Y386542D03*
X358169Y265368D03*
X358222Y292641D03*
X413400Y340600D03*
X417400D03*
X449400Y330800D03*
X427500Y340600D03*
X432900Y340900D03*
X445400Y330800D03*
X447300Y340900D03*
X391900Y340700D03*
X450200Y322200D03*
X510000Y351600D03*
X506000D03*
X505379Y341811D03*
X501281D03*
X509517Y341846D03*
X502200Y360609D03*
X455900Y340800D03*
X478618Y339442D03*
X547908Y331732D03*
X541747Y331765D03*
X529947Y331800D03*
X525522Y341846D03*
X529622D03*
X558000Y348300D03*
X554000D03*
X533947Y331800D03*
X540200Y351400D03*
X536200D03*
X545200D03*
X549200D03*
X633000Y62300D03*
X636000Y203300D03*
X632000D03*
X624000D03*
X628000D03*
X618026Y261552D03*
X611526D03*
X659850Y46800D03*
X641003Y62309D03*
X640000Y203300D03*
X648000D03*
X652000D03*
X644000D03*
X656000D03*
X660000D03*
X645500Y261200D03*
X652000D03*
X672131Y383183D03*
X717500Y135250D03*
X713500D03*
X710800Y214600D03*
X719700D03*
X785350Y84300D03*
X794500Y137400D03*
X782500D03*
X798500D03*
X796500Y229300D03*
G54D40*
X352230Y247771D03*
Y255371D03*
X352228Y275887D03*
Y283487D03*
X352254Y269441D03*
Y261841D03*
X352222Y297541D03*
Y289941D03*
X352214Y303962D03*
Y311562D03*
X625300Y103200D03*
Y110800D03*
X625281Y127708D03*
Y135308D03*
X624026Y267252D03*
Y259652D03*
X605526Y267252D03*
Y259652D03*
X627570Y452930D03*
Y460530D03*
X619200Y441200D03*
Y433600D03*
X626900Y441200D03*
Y433600D03*
X687375Y177704D03*
Y185304D03*
X696761Y177683D03*
Y185283D03*
X639500Y266800D03*
Y259200D03*
X658000Y266800D03*
Y259200D03*
X706195Y177658D03*
Y185258D03*
X783000Y107700D03*
Y115300D03*
X781507Y129393D03*
Y121793D03*
G54D13*
X153458Y418270D03*
X265312Y59618D03*
X622826Y234952D03*
X585300Y449500D03*
X663745Y23414D03*
X670777Y135318D03*
X670718Y141825D03*
X687800Y128700D03*
X680182Y128735D03*
X644723Y144911D03*
X644750Y134900D03*
X644700Y148800D03*
X674692Y195715D03*
X667012Y195705D03*
X658000Y238400D03*
X688112Y480221D03*
X708588Y145327D03*
X701689Y169842D03*
X709210D03*
X729655Y195527D03*
X724904Y329638D03*
G54D50*
X433218Y253101D03*
X436818D03*
X472600Y278500D03*
X476200D03*
X605026Y238652D03*
X608626D03*
X647700Y125850D03*
X651300D03*
X697700Y119500D03*
X640700Y234700D03*
X644300D03*
X711700Y119500D03*
X715300D03*
X704700D03*
X708300D03*
X701300D03*
X711001Y195267D03*
X714601D03*
G54D14*
X148138Y423870D03*
X155738D03*
X172738Y425870D03*
X165138D03*
X172738Y417870D03*
X165138D03*
X148138Y431470D03*
X155738D03*
X248600Y238500D03*
X241000D03*
X248600Y230900D03*
X241000D03*
X248600Y223300D03*
X241000D03*
X248600Y215700D03*
X241000D03*
X248600Y208100D03*
X241000D03*
X255200Y375750D03*
X262800D03*
X281300Y156500D03*
X273700D03*
X281300Y147500D03*
X273700D03*
X281300Y231000D03*
X273700D03*
X281300Y189500D03*
X273700D03*
X281300Y239500D03*
X273700D03*
X281300Y198000D03*
X273700D03*
X522812Y470071D03*
X515212D03*
X523000Y462400D03*
X515400D03*
X617726Y244452D03*
X625326D03*
X610826D03*
X603226D03*
X675462Y162183D03*
X667862D03*
X675597Y177941D03*
X667997D03*
X675735Y187351D03*
X668135D03*
X645800Y244000D03*
X638200D03*
X652700D03*
X660300D03*
X643100Y364900D03*
X650700D03*
X682000Y466700D03*
X689600D03*
X682000Y474366D03*
X689600D03*
X719304Y345038D03*
X726904D03*
X719304Y353038D03*
X726904D03*
X797800Y112500D03*
X790200D03*
X802307Y124593D03*
X794707D03*
G54D41*
X371698Y341070D03*
X376784Y310847D03*
X419979Y263835D03*
X398230Y331430D03*
X483144Y359195D03*
X450841Y351640D03*
X454341Y356355D03*
X478300Y371800D03*
X524250Y476000D03*
X516750D03*
X574100Y483400D03*
Y487900D03*
X641800Y166000D03*
X679384Y201545D03*
X690050Y236469D03*
X692300Y210200D03*
X678789Y262854D03*
X735100Y97900D03*
X734252Y160315D03*
X757115Y136383D03*
X753800Y169500D03*
X757115Y140433D03*
X754021Y145050D03*
X754300Y160800D03*
X757115Y132181D03*
X706047Y138406D03*
X736879Y151899D03*
X721404Y333538D03*
X791800Y106500D03*
X796807Y130593D03*
X779841Y182831D03*
X787750Y182850D03*
G54D23*
X262600Y411100D03*
X301000Y159200D03*
X300500Y199200D03*
Y241700D03*
X362868Y263441D03*
X362689Y291541D03*
X631781Y128708D03*
X639120Y452330D03*
X776500Y108700D03*
X790000Y92700D03*
X776500D03*
G54D32*
X283000Y289700D03*
X316786Y389942D03*
X358169Y268768D03*
X358222Y296041D03*
X413400Y344000D03*
X417400D03*
X449400Y334200D03*
X427500Y344000D03*
X432900Y344300D03*
X445400Y334200D03*
X447300Y344300D03*
X391900Y344100D03*
X450200Y325600D03*
X510000Y355000D03*
X506000D03*
X505379Y345211D03*
X501281D03*
X509517Y345246D03*
X455900Y344200D03*
X478618Y342842D03*
X502200Y364009D03*
X547908Y335132D03*
X541747Y335165D03*
X529947Y335200D03*
X525522Y345246D03*
X529622D03*
X558000Y351700D03*
X554000D03*
X533947Y335200D03*
X540200Y354800D03*
X536200D03*
X545200D03*
X549200D03*
X633000Y65700D03*
X636000Y206700D03*
X632000D03*
X624000D03*
X628000D03*
X618026Y264952D03*
X611526D03*
X659850Y50200D03*
X641003Y65709D03*
X640000Y206700D03*
X648000D03*
X652000D03*
X644000D03*
X656000D03*
X660000D03*
X645500Y264600D03*
X652000D03*
X672131Y386583D03*
X717500Y138650D03*
X713500D03*
X710800Y218000D03*
X719700D03*
X785350Y87700D03*
X794500Y140800D03*
X782500D03*
X798500D03*
X796500Y232700D03*
G54D24*
X285500Y55518D03*
X281700D03*
X426300Y245700D03*
X644950Y36700D03*
X660300Y150000D03*
X667300Y151100D03*
X689132Y196295D03*
X669000Y246200D03*
X804500Y178530D03*
G54D15*
X166138Y432870D03*
X542495Y471383D03*
X604226Y252452D03*
X639200Y252000D03*
G54D33*
X321787Y278970D03*
X325287D03*
X444850Y243879D03*
X438000D03*
X430470D03*
X475500D03*
X459500D03*
X451500D03*
X467600D03*
X645248Y47895D03*
X648748D03*
X652248D03*
X656051Y46793D03*
X660450Y135900D03*
X716517Y189323D03*
X771607Y127493D03*
X800600Y182130D03*
G54D42*
X375098Y341070D03*
X380184Y310847D03*
X423379Y263835D03*
X401630Y331430D03*
X486544Y359195D03*
X454241Y351640D03*
X457741Y356355D03*
X481700Y371800D03*
X527650Y476000D03*
X520150D03*
X577500Y483400D03*
Y487900D03*
X645200Y166000D03*
X682784Y201545D03*
X693450Y236469D03*
X695700Y210200D03*
X682189Y262854D03*
X738500Y97900D03*
X737652Y160315D03*
X757200Y169500D03*
X757421Y145050D03*
X757700Y160800D03*
X709447Y138406D03*
X740279Y151899D03*
X724804Y333538D03*
X795200Y106500D03*
X760515Y136383D03*
Y140433D03*
Y132181D03*
X800207Y130593D03*
X783241Y182831D03*
X791150Y182850D03*
G54D51*
X555355Y470540D03*
X562855Y474415D03*
Y466665D03*
X555550Y484900D03*
X563050Y481025D03*
Y488775D03*
X791750Y78500D03*
X799250Y82375D03*
Y74625D03*
G54D60*
X658500Y371350D03*
G54D25*
X285500Y59118D03*
X281700D03*
X426300Y249300D03*
X644950Y40300D03*
X660300Y153600D03*
X667300Y154700D03*
X689132Y199895D03*
X669000Y249800D03*
X804500Y182130D03*
G54D43*
X381083Y314895D03*
X402658Y262952D03*
X432789Y267240D03*
X412950Y330250D03*
X440186Y351341D03*
X411420Y335630D03*
X501900Y194800D03*
X490044Y354873D03*
X481800Y367500D03*
Y363400D03*
X498500Y368350D03*
X545695Y480090D03*
X569939Y461261D03*
X574033Y476488D03*
X657713Y166929D03*
X688200Y210200D03*
X672900Y288000D03*
X682189Y268500D03*
X740279Y155899D03*
X716046Y276558D03*
X762570Y81900D03*
X762540Y77810D03*
X762570Y86100D03*
G54D52*
X529450Y485100D03*
X521950Y481225D03*
Y488975D03*
X757650Y91855D03*
Y99605D03*
X765150Y95730D03*
G54D61*
X724380Y291446D03*
Y289476D03*
Y287511D03*
Y285541D03*
Y283571D03*
Y281601D03*
Y279636D03*
Y277666D03*
Y275696D03*
Y273731D03*
Y271761D03*
Y269791D03*
Y267826D03*
Y265856D03*
Y263886D03*
Y261916D03*
Y259951D03*
Y257981D03*
Y256011D03*
Y254046D03*
Y252076D03*
Y250106D03*
Y248141D03*
Y246171D03*
Y244201D03*
Y242231D03*
Y240266D03*
Y238296D03*
X800080D03*
Y240266D03*
Y242231D03*
Y244201D03*
Y246171D03*
Y248141D03*
Y250106D03*
Y252076D03*
Y254046D03*
Y256011D03*
Y257981D03*
Y259951D03*
Y261916D03*
Y263886D03*
Y265856D03*
Y267826D03*
Y269791D03*
Y271761D03*
Y273731D03*
Y275696D03*
Y277666D03*
Y279636D03*
Y281601D03*
Y283571D03*
Y285541D03*
Y287511D03*
Y289476D03*
Y291446D03*
G54D34*
X321787Y275370D03*
X325287D03*
X444850Y240279D03*
X438000D03*
X430470D03*
X475500D03*
X459500D03*
X451500D03*
X467600D03*
X645248Y44295D03*
X648748D03*
X652248D03*
X656051Y43193D03*
X660450Y132300D03*
X716517Y185723D03*
X771607Y123893D03*
X800600Y178530D03*
G54D16*
X171738Y432870D03*
X548095Y471383D03*
X609826Y252452D03*
X644800Y252000D03*
G54D44*
X377683Y314895D03*
X399258Y262952D03*
X429389Y267240D03*
X409550Y330250D03*
X436786Y351341D03*
X408020Y335630D03*
X498500Y194800D03*
X486644Y354873D03*
X478400Y367500D03*
Y363400D03*
X495100Y368350D03*
X542295Y480090D03*
X570633Y476488D03*
X566539Y461261D03*
X654313Y166929D03*
X684800Y210200D03*
X669500Y288000D03*
X678789Y268500D03*
X759170Y81900D03*
X759140Y77810D03*
X759170Y86100D03*
X736879Y155899D03*
X712646Y276558D03*
G54D53*
X532812Y444771D03*
X537812D03*
X542812D03*
X547812D03*
Y464771D03*
X542812D03*
X537812D03*
X532812D03*
X800000Y172000D03*
X795000D03*
X790000D03*
X785000D03*
Y152000D03*
X790000D03*
X795000D03*
X800000D03*
G54D62*
X713712Y470871D03*
Y465871D03*
Y460871D03*
Y455871D03*
X733712D03*
Y460871D03*
Y465871D03*
Y470871D03*
G54D17*
X153038Y443136D03*
X171038D03*
G54D35*
X290425Y297650D03*
X292395D03*
X294360D03*
X296330D03*
X298300D03*
X300270D03*
X302235D03*
X304205D03*
X306175D03*
X308140D03*
X310110D03*
X312080D03*
X314045D03*
X316015D03*
X317985D03*
X319955D03*
X321920D03*
X323890D03*
Y373350D03*
X321920D03*
X319955D03*
X317985D03*
X316015D03*
X314045D03*
X312080D03*
X310110D03*
X308140D03*
X306175D03*
X304205D03*
X302235D03*
X300270D03*
X298300D03*
X296330D03*
X294360D03*
X292395D03*
X290425D03*
X325860Y297650D03*
X327825D03*
X329795D03*
X331765D03*
X333730D03*
X335700D03*
X337670D03*
X339640D03*
X341605D03*
X343575D03*
Y373350D03*
X341605D03*
X339640D03*
X337670D03*
X335700D03*
X333730D03*
X331765D03*
X329795D03*
X327825D03*
X325860D03*
G54D26*
X280800Y141000D03*
X280300Y163000D03*
X280800Y204500D03*
Y224500D03*
X280300Y183000D03*
Y246000D03*
X624326Y252452D03*
X659300Y252000D03*
X725904Y338538D03*
G54D18*
X254800Y415000D03*
X316100Y290100D03*
X342200Y285800D03*
Y277770D03*
X380771Y332810D03*
X476300Y270600D03*
X476200Y262500D03*
X476500Y249200D03*
X476400Y254800D03*
X557800Y461260D03*
X520200Y456800D03*
X608526Y234952D03*
X651254Y138591D03*
X650317Y116114D03*
Y119614D03*
X676752Y150915D03*
Y154415D03*
X686202Y145315D03*
X686200Y151100D03*
X686100Y157350D03*
X664200Y128650D03*
X644200Y238400D03*
X721933Y195408D03*
X707262Y195365D03*
X699652Y194895D03*
G54D36*
X380500Y173000D03*
Y175200D03*
X382700Y173000D03*
Y175200D03*
X386500Y173000D03*
Y175200D03*
X388700Y173000D03*
Y175200D03*
X392500Y173000D03*
Y175200D03*
X394700Y173000D03*
Y175200D03*
X398500Y173000D03*
Y175200D03*
X400700Y173000D03*
Y175200D03*
X404500Y173000D03*
Y175200D03*
X406700Y173000D03*
Y175200D03*
X412700Y173000D03*
Y175200D03*
X410500Y173000D03*
Y175200D03*
X416500Y173000D03*
Y175200D03*
X418700Y173000D03*
Y175200D03*
X422500Y173000D03*
Y175200D03*
X428500Y173000D03*
Y175200D03*
X424700Y173000D03*
Y175200D03*
X430700Y173000D03*
Y175200D03*
X434500Y173000D03*
Y175200D03*
X436700Y173000D03*
Y175200D03*
X440500Y173000D03*
Y175200D03*
X442700Y173000D03*
Y175200D03*
X446500Y173000D03*
Y175200D03*
X448700Y173000D03*
Y175200D03*
X423297Y257900D03*
Y260100D03*
X407500Y253900D03*
Y256100D03*
X419300Y257900D03*
Y260100D03*
X411400Y253900D03*
Y256100D03*
X442500Y276000D03*
Y278200D03*
X440000Y276000D03*
Y278200D03*
X447500Y276000D03*
Y278200D03*
X452500Y173000D03*
Y175200D03*
X454700Y173000D03*
Y175200D03*
X458500Y173000D03*
Y175200D03*
X460700Y173000D03*
Y175200D03*
X464500Y173000D03*
Y175200D03*
X466700Y173000D03*
Y175200D03*
X470500Y173000D03*
Y175200D03*
X472700Y173000D03*
Y175200D03*
X478100Y154300D03*
Y156500D03*
X480400Y154300D03*
Y156500D03*
X485100Y154300D03*
Y156500D03*
X487400Y154300D03*
Y156500D03*
X492100Y154300D03*
Y156500D03*
X494400Y154300D03*
Y156500D03*
X499500Y154300D03*
Y156500D03*
X501800Y154300D03*
Y156500D03*
X504800Y159800D03*
Y162000D03*
X507100Y159800D03*
Y162000D03*
X451500Y209400D03*
Y211600D03*
X494100Y289600D03*
Y291800D03*
X486250Y285250D03*
Y287450D03*
X466658Y276174D03*
Y278374D03*
X468968Y276174D03*
Y278374D03*
X462553Y275970D03*
Y278170D03*
X474500Y299900D03*
X458700Y298100D03*
X462600Y298200D03*
X454700Y276000D03*
Y278200D03*
X458700Y276000D03*
Y278200D03*
X450000Y276000D03*
Y278200D03*
X458667Y315905D03*
Y318105D03*
X486308Y316042D03*
Y318242D03*
X451100Y315700D03*
Y317900D03*
X474500Y302100D03*
X458700Y300300D03*
X462600Y300400D03*
X515055Y173622D03*
Y175822D03*
X517255Y173622D03*
Y175822D03*
X524700Y173700D03*
X526900D03*
X533093Y220867D03*
Y223067D03*
X530893Y220867D03*
Y223067D03*
X524700Y175900D03*
X526900D03*
X534120Y240257D03*
Y242457D03*
X531920Y240257D03*
Y242457D03*
X512700Y317400D03*
Y319600D03*
X677505Y112037D03*
X667843Y170060D03*
Y172260D03*
X680671Y133232D03*
Y135432D03*
X673887Y133186D03*
Y135386D03*
X677505Y114237D03*
X686636Y133246D03*
Y135446D03*
X671452Y200715D03*
Y202915D03*
X699245Y111675D03*
Y113875D03*
G54D63*
X739680Y429140D03*
Y438140D03*
G54D27*
X275200Y141000D03*
X274700Y163000D03*
X275200Y204500D03*
Y224500D03*
X274700Y183000D03*
Y246000D03*
X618726Y252452D03*
X653700Y252000D03*
X720304Y338538D03*
G54D54*
X622826Y238652D03*
X619226D03*
X644700Y131100D03*
X641100D03*
X657800Y234700D03*
X654200D03*
X723200Y119500D03*
X719600D03*
G54D45*
X371648Y335023D03*
X427166Y297245D03*
X431102Y293307D03*
X442908Y293298D03*
X419292Y297245D03*
X423221Y293300D03*
X423228Y305118D03*
X431102Y301181D03*
X423229Y320867D03*
X431105Y309010D03*
X419291Y309055D03*
X442913Y305118D03*
X438976Y301181D03*
Y309055D03*
X434000Y322200D03*
X503468Y324325D03*
X497550Y324150D03*
X496000Y336000D03*
X506700Y336200D03*
X501400Y336000D03*
X468500Y333500D03*
X472600Y310400D03*
X466535Y305118D03*
X557500Y343350D03*
X552100Y343300D03*
X524500Y335500D03*
X516194Y332572D03*
X631700Y198500D03*
X626400D03*
X650936Y160874D03*
X656878Y161079D03*
X695770Y125429D03*
X693674Y132295D03*
X648035Y154330D03*
X642300Y198500D03*
X637000D03*
X646004Y179768D03*
X650722Y183439D03*
X646000Y185900D03*
X694087Y201724D03*
X690207Y205597D03*
X657113Y198415D03*
X651722Y198588D03*
X734500Y113400D03*
X737100Y103000D03*
X730200Y98200D03*
X719500Y102900D03*
X742700Y103100D03*
X739900Y112500D03*
X745700Y108700D03*
X724200Y110700D03*
X719000Y112700D03*
X715100Y107300D03*
X708300Y113300D03*
X725600Y103600D03*
X713700Y112500D03*
X724600Y97100D03*
X717087Y97384D03*
X703600Y110600D03*
X729400Y111800D03*
X734500Y139200D03*
X743400Y139100D03*
X738000Y133900D03*
X746400Y134600D03*
X736730Y166522D03*
X733372Y130235D03*
X742700Y130600D03*
X736800Y125200D03*
X733600Y120500D03*
X738200Y117600D03*
X741500Y146500D03*
X747700Y114800D03*
X747200Y127400D03*
X744222Y120527D03*
X716040Y176322D03*
X699999Y132427D03*
X727700Y118000D03*
X707861Y133930D03*
X752500Y127500D03*
X733792Y175376D03*
X733500Y146000D03*
X721500Y202600D03*
X710687Y202564D03*
X726032Y205904D03*
X736078Y181764D03*
X745659Y183788D03*
X746691Y189552D03*
X734043Y187231D03*
X745778Y178204D03*
X742978Y206202D03*
X715300Y214400D03*
G54D64*
G01X-34018Y-300855D02*
G02I-12000J0D01*
G01X-39168D02*
G02I-6850J0D01*
G01X-30018D02*
X-62018D01*
G01X-30018Y-316855D02*
Y-396855D01*
G01D02*
X1320682D01*
G01X-30018Y-352355D02*
X1320682D01*
G01X-46018Y-316855D02*
Y-284855D01*
G01X-30018Y-316855D02*
X1320682D01*
G01X533182D02*
Y-396855D01*
G01X670682Y-316855D02*
Y-396855D01*
G01X785682Y-316855D02*
Y-396855D01*
G01X953182Y-316855D02*
Y-396855D01*
G01X1123182Y-316855D02*
Y-396855D01*
G01X1320682Y-316855D02*
Y-396855D01*
G01X1348682Y-300855D02*
G02I-12000J0D01*
G01X1343532D02*
G02I-6850J0D01*
G01X1336682Y-316855D02*
Y-284855D01*
G01X1352682Y-300855D02*
X1320682D01*
G54D19*
X251200Y415000D03*
X312500Y290100D03*
X338600Y285800D03*
Y277770D03*
X377171Y332810D03*
X472700Y270600D03*
X472600Y262500D03*
X472900Y249200D03*
X472800Y254800D03*
X554200Y461260D03*
X516600Y456800D03*
X604926Y234952D03*
X647654Y138591D03*
X646717Y116114D03*
Y119614D03*
X673152Y150915D03*
Y154415D03*
X682602Y145315D03*
X682600Y151100D03*
X682500Y157350D03*
X660600Y128650D03*
X696052Y194895D03*
X640600Y238400D03*
X718333Y195408D03*
X703662Y195365D03*
G54D55*
X658116Y36660D03*
Y34100D03*
Y31540D03*
X651616D03*
Y36660D03*
G54D28*
X290000Y136500D03*
Y147500D03*
Y167500D03*
Y156500D03*
Y239500D03*
Y209000D03*
Y198000D03*
Y220000D03*
Y231000D03*
Y178500D03*
Y189500D03*
Y250500D03*
G54D46*
X358550Y319900D03*
X354800D03*
X351050D03*
Y330500D03*
X354800D03*
X358550D03*
X674989Y255684D03*
X678739D03*
X682489D03*
Y245084D03*
X678739D03*
X674989D03*
G54D37*
X378811Y198292D03*
X381011D03*
X378811Y200592D03*
X381011D03*
X378811Y203792D03*
X381011D03*
X378811Y206092D03*
X381011D03*
X378811Y211592D03*
X381011D03*
X378811Y209292D03*
X381011D03*
X378811Y214792D03*
X381011D03*
X378811Y217092D03*
X381011D03*
X399400Y226400D03*
X401600D03*
X445568Y297155D03*
X447768D03*
X489050Y210650D03*
X491250D03*
X508338Y233748D03*
X510538D03*
X508338Y214971D03*
X510538D03*
X508338Y225790D03*
X510538D03*
X508338Y217456D03*
X510538D03*
X489100Y229900D03*
X491300D03*
X489117Y234208D03*
X491317D03*
X489100Y227400D03*
X491300D03*
X508338Y231089D03*
X510538D03*
X508338Y223290D03*
X510538D03*
X489950Y285450D03*
X492150D03*
X489900Y273650D03*
X492100D03*
X489900Y265600D03*
X492100D03*
X489950Y277500D03*
X492150D03*
X489050Y238200D03*
X491250D03*
X692612Y164865D03*
X694812D03*
X692685Y156336D03*
X694885D03*
X692450Y168950D03*
X694650D03*
X692612Y162665D03*
X694812D03*
X692685Y158536D03*
X694885D03*
X692600Y150050D03*
X694800D03*
X692602Y145815D03*
X694802D03*
X692450Y171150D03*
X694650D03*
X692600Y152250D03*
X694800D03*
X670097Y129076D03*
X672297D03*
X657737Y194808D03*
X659937D03*
X701341Y81023D03*
X703541D03*
X701344Y83270D03*
X703544D03*
X712560Y83760D03*
X714760D03*
X712559Y85992D03*
X714759D03*
X698923Y164914D03*
X701123D03*
X698950Y152240D03*
X701150D03*
X705362Y164913D03*
X707562D03*
X725142Y145165D03*
X727342D03*
X725142Y151175D03*
X727342D03*
X725142Y157715D03*
X727342D03*
X723922Y126891D03*
X726122D03*
X725142Y170065D03*
X727342D03*
X705362Y162713D03*
X707562D03*
X705321Y158619D03*
X707521D03*
X705352Y150035D03*
X707552D03*
X698923Y162714D03*
X701123D03*
X698944Y158543D03*
X701144D03*
X698950Y150040D03*
X701150D03*
X698952Y145865D03*
X701152D03*
X705321Y156419D03*
X707521D03*
X698944Y156343D03*
X701144D03*
X705352Y152235D03*
X707552D03*
X725142Y176315D03*
X727342D03*
X725142Y189185D03*
X727342D03*
X725142Y182795D03*
X727342D03*
G54D65*
G01X121778Y-377522D02*
X122652Y-376647D01*
X123307Y-375189D01*
X123744Y-373146D01*
X123307Y-371397D01*
X122434Y-370230D01*
X120905Y-369355D01*
X115010D01*
Y-386855D01*
X122215D01*
X123744Y-385689D01*
X124617Y-383938D01*
X125054Y-381897D01*
X124617Y-379855D01*
X123307Y-378105D01*
X121778Y-377522D01*
X115010D01*
G01X134475Y-386855D02*
Y-375189D01*
G01Y-377522D02*
X135567Y-376355D01*
X136659Y-375480D01*
X138187Y-375189D01*
X139278Y-375480D01*
X140589Y-376355D01*
G01X150447Y-392105D02*
X151757Y-392688D01*
X153504Y-392105D01*
X154595Y-390939D01*
X155469Y-389480D01*
X156778Y-384814D01*
X159617Y-375189D01*
G01X152630D02*
X156778Y-384814D01*
G01X176025Y-376647D02*
X174497Y-375480D01*
X173187Y-375189D01*
X171440Y-375772D01*
X170130Y-376938D01*
X169257Y-378980D01*
X169038Y-381022D01*
X169257Y-383064D01*
X170130Y-384814D01*
X171440Y-386272D01*
X173187Y-386855D01*
X174715Y-386272D01*
X176025Y-385105D01*
G01X186757Y-378980D02*
X193744D01*
X193089Y-376938D01*
X191997Y-375772D01*
X190469Y-375189D01*
X188940Y-375480D01*
X187630Y-376355D01*
X186757Y-378397D01*
X186320Y-380147D01*
Y-381897D01*
X186757Y-383647D01*
X187849Y-385397D01*
X189159Y-386563D01*
X190687Y-386855D01*
X192215Y-386272D01*
X193744Y-384522D01*
G01X229835Y-370814D02*
X228525Y-369938D01*
X226997Y-369355D01*
X225250D01*
X223285Y-370230D01*
X221757Y-371688D01*
X220665Y-373439D01*
X219792Y-376355D01*
X219573Y-378980D01*
X220010Y-381605D01*
X220665Y-383355D01*
X221975Y-385105D01*
X223504Y-386272D01*
X225032Y-386855D01*
X226560D01*
X228089Y-386272D01*
X229399Y-385397D01*
X230491Y-384231D01*
G01X246462Y-386855D02*
Y-375189D01*
G01Y-377230D02*
X245589Y-376064D01*
X244278Y-375480D01*
X242750Y-375189D01*
X241222Y-375772D01*
X239912Y-376938D01*
X239038Y-378688D01*
X238602Y-381022D01*
X239038Y-383355D01*
X239912Y-385105D01*
X241222Y-386272D01*
X242750Y-386855D01*
X244278Y-386563D01*
X245589Y-385689D01*
X246462Y-384522D01*
G01X256320Y-386855D02*
Y-375189D01*
G01Y-378105D02*
X257194Y-376647D01*
X258504Y-375480D01*
X260250Y-375189D01*
X261778Y-375480D01*
X263089Y-376647D01*
X263744Y-378688D01*
Y-386855D01*
G01X272947Y-392105D02*
X274257Y-392688D01*
X276004Y-392105D01*
X277095Y-390939D01*
X277969Y-389480D01*
X279278Y-384814D01*
X282117Y-375189D01*
G01X275130D02*
X279278Y-384814D01*
G01X295032Y-386855D02*
X293722Y-386563D01*
X292412Y-385397D01*
X291538Y-383355D01*
X291102Y-381022D01*
X291538Y-378688D01*
X292412Y-376647D01*
X293722Y-375480D01*
X295032Y-375189D01*
X296342Y-375480D01*
X297652Y-376647D01*
X298525Y-378688D01*
X298744Y-381022D01*
X298525Y-383355D01*
X297652Y-385397D01*
X296342Y-386563D01*
X295032Y-386855D01*
G01X308820D02*
Y-375189D01*
G01Y-378105D02*
X309694Y-376647D01*
X311004Y-375480D01*
X312750Y-375189D01*
X314278Y-375480D01*
X315589Y-376647D01*
X316244Y-378688D01*
Y-386855D01*
G01X342947Y-384522D02*
X344694Y-385980D01*
X346659Y-386855D01*
X348405D01*
X350152Y-385980D01*
X351462Y-384522D01*
X352117Y-382480D01*
X351680Y-380439D01*
X350589Y-378688D01*
X348624Y-377522D01*
X346004Y-376938D01*
X344475Y-375772D01*
X343820Y-373730D01*
X344257Y-371688D01*
X345349Y-370230D01*
X346877Y-369355D01*
X348405D01*
X349934Y-369938D01*
X351244Y-371397D01*
G01X369835Y-370814D02*
X368525Y-369938D01*
X366997Y-369355D01*
X365250D01*
X363285Y-370230D01*
X361757Y-371688D01*
X360665Y-373439D01*
X359792Y-376355D01*
X359573Y-378980D01*
X360010Y-381605D01*
X360665Y-383355D01*
X361975Y-385105D01*
X363504Y-386272D01*
X365032Y-386855D01*
X366560D01*
X368089Y-386272D01*
X369399Y-385397D01*
X370491Y-384231D01*
G01X387335Y-370814D02*
X386025Y-369938D01*
X384497Y-369355D01*
X382750D01*
X380785Y-370230D01*
X379257Y-371688D01*
X378165Y-373439D01*
X377292Y-376355D01*
X377073Y-378980D01*
X377510Y-381605D01*
X378165Y-383355D01*
X379475Y-385105D01*
X381004Y-386272D01*
X382532Y-386855D01*
X384060D01*
X385589Y-386272D01*
X386899Y-385397D01*
X387991Y-384231D01*
G01X210605Y-341855D02*
Y-324355D01*
X216282Y-338938D01*
X221959Y-324355D01*
Y-341855D01*
G01X233782D02*
X232472Y-341563D01*
X231162Y-340397D01*
X230288Y-338355D01*
X229852Y-336022D01*
X230288Y-333688D01*
X231162Y-331647D01*
X232472Y-330480D01*
X233782Y-330189D01*
X235092Y-330480D01*
X236402Y-331647D01*
X237275Y-333688D01*
X237494Y-336022D01*
X237275Y-338355D01*
X236402Y-340397D01*
X235092Y-341563D01*
X233782Y-341855D01*
G01X255212Y-324355D02*
Y-341855D01*
G01Y-339231D02*
X254339Y-340689D01*
X253028Y-341563D01*
X251500Y-341855D01*
X249754Y-341272D01*
X248444Y-339814D01*
X247570Y-338064D01*
X247352Y-336022D01*
X247570Y-333980D01*
X248444Y-332230D01*
X249754Y-330772D01*
X251500Y-330189D01*
X253028Y-330480D01*
X254120Y-331064D01*
X255212Y-332230D01*
G01X265507Y-333980D02*
X272494D01*
X271839Y-331938D01*
X270747Y-330772D01*
X269219Y-330189D01*
X267690Y-330480D01*
X266380Y-331355D01*
X265507Y-333397D01*
X265070Y-335147D01*
Y-336897D01*
X265507Y-338647D01*
X266599Y-340397D01*
X267909Y-341563D01*
X269437Y-341855D01*
X270965Y-341272D01*
X272494Y-339522D01*
G01X286282Y-341855D02*
Y-324355D01*
G01X566882Y-386855D02*
Y-369355D01*
X564262Y-372855D01*
G01Y-386855D02*
X569502D01*
G01X580234Y-379564D02*
X581762Y-377522D01*
X583072Y-376355D01*
X584819Y-375772D01*
X586347Y-376355D01*
X587439Y-377522D01*
X588312Y-379272D01*
X588530Y-381313D01*
X588312Y-383064D01*
X587439Y-384814D01*
X586128Y-386272D01*
X584600Y-386855D01*
X582854Y-386272D01*
X581325Y-384522D01*
X580452Y-381897D01*
X580234Y-378980D01*
X580670Y-375189D01*
X581325Y-373146D01*
X582417Y-371105D01*
X583945Y-369647D01*
X585474Y-369355D01*
X587002Y-369938D01*
X588094Y-371397D01*
G01X597079Y-383355D02*
X598388Y-385397D01*
X600135Y-386563D01*
X602100Y-386855D01*
X603847Y-386563D01*
X605594Y-385105D01*
X606685Y-383355D01*
X606904Y-381605D01*
X606467Y-379564D01*
X604939Y-378105D01*
X603410Y-377522D01*
X601445D01*
G01X603410D02*
X604720Y-376647D01*
X605812Y-375189D01*
X606249Y-373439D01*
X605812Y-371688D01*
X604720Y-370230D01*
X602755Y-369355D01*
X600790Y-369647D01*
X598825Y-370814D01*
G01X619382Y-386855D02*
Y-369355D01*
X616762Y-372855D01*
G01Y-386855D02*
X622002D01*
G01X632734Y-379564D02*
X634262Y-377522D01*
X635572Y-376355D01*
X637319Y-375772D01*
X638847Y-376355D01*
X639939Y-377522D01*
X640812Y-379272D01*
X641030Y-381313D01*
X640812Y-383064D01*
X639939Y-384814D01*
X638628Y-386272D01*
X637100Y-386855D01*
X635354Y-386272D01*
X633825Y-384522D01*
X632952Y-381897D01*
X632734Y-378980D01*
X633170Y-375189D01*
X633825Y-373146D01*
X634917Y-371105D01*
X636445Y-369647D01*
X637974Y-369355D01*
X639502Y-369938D01*
X640594Y-371397D01*
G01X553765Y-341855D02*
Y-324355D01*
X559005D01*
X560752Y-325230D01*
X562062Y-327272D01*
X562499Y-329605D01*
X562062Y-331938D01*
X560970Y-333688D01*
X559005Y-334564D01*
X553765D01*
G01X580435Y-325814D02*
X579125Y-324938D01*
X577597Y-324355D01*
X575850D01*
X573885Y-325230D01*
X572357Y-326688D01*
X571265Y-328439D01*
X570392Y-331355D01*
X570173Y-333980D01*
X570610Y-336605D01*
X571265Y-338355D01*
X572575Y-340105D01*
X574104Y-341272D01*
X575632Y-341855D01*
X577160D01*
X578689Y-341272D01*
X579999Y-340397D01*
X581091Y-339231D01*
G01X594878Y-332522D02*
X595752Y-331647D01*
X596407Y-330189D01*
X596844Y-328146D01*
X596407Y-326397D01*
X595534Y-325230D01*
X594005Y-324355D01*
X588110D01*
Y-341855D01*
X595315D01*
X596844Y-340689D01*
X597717Y-338938D01*
X598154Y-336897D01*
X597717Y-334855D01*
X596407Y-333105D01*
X594878Y-332522D01*
X588110D01*
G01X604082Y-347688D02*
X617182D01*
G01X623110Y-341855D02*
Y-324355D01*
X633154Y-341855D01*
Y-324355D01*
G01X645632Y-341855D02*
X643885Y-341563D01*
X642357Y-340397D01*
X641047Y-338647D01*
X640173Y-336605D01*
X639737Y-334272D01*
Y-331938D01*
X640173Y-329605D01*
X641047Y-327563D01*
X642357Y-325814D01*
X643885Y-324647D01*
X645632Y-324355D01*
X647378Y-324647D01*
X648907Y-325814D01*
X650217Y-327563D01*
X651091Y-329605D01*
X651527Y-331938D01*
Y-334272D01*
X651091Y-336605D01*
X650217Y-338647D01*
X648907Y-340397D01*
X647378Y-341563D01*
X645632Y-341855D01*
G01X696473Y-324355D02*
X701932Y-341855D01*
X707391Y-324355D01*
G01X723799Y-341855D02*
X715065D01*
Y-324355D01*
X723799D01*
G01X720305Y-332813D02*
X715065D01*
G01X732565Y-341855D02*
Y-324355D01*
X738024D01*
X739770Y-325230D01*
X740862Y-326397D01*
X741299Y-328730D01*
X740862Y-331064D01*
X739552Y-332522D01*
X738024Y-333397D01*
X732565D01*
G01X738024D02*
X741299Y-341855D01*
G01X754432Y-342438D02*
X753995Y-342147D01*
Y-341563D01*
X754432Y-341272D01*
X754869Y-341563D01*
Y-342147D01*
X754432Y-342438D01*
G01X728182Y-386855D02*
Y-369355D01*
X725562Y-372855D01*
G01Y-386855D02*
X730802D01*
G01X893886Y-377522D02*
X893012Y-376647D01*
X892357Y-375189D01*
X891920Y-373146D01*
X892357Y-371397D01*
X893230Y-370230D01*
X894759Y-369355D01*
X900654D01*
Y-386855D01*
X893449D01*
X891920Y-385689D01*
X891047Y-383938D01*
X890610Y-381897D01*
X891047Y-379855D01*
X892357Y-378105D01*
X893886Y-377522D01*
X900654D01*
G01X882717Y-384522D02*
X880970Y-385980D01*
X879005Y-386855D01*
X877259D01*
X875512Y-385980D01*
X874202Y-384522D01*
X873547Y-382480D01*
X873984Y-380439D01*
X875075Y-378688D01*
X877040Y-377522D01*
X879660Y-376938D01*
X881189Y-375772D01*
X881844Y-373730D01*
X881407Y-371688D01*
X880315Y-370230D01*
X878787Y-369355D01*
X877259D01*
X875730Y-369938D01*
X874420Y-371397D01*
G01X866309Y-386855D02*
Y-369355D01*
X860632Y-383938D01*
X854955Y-369355D01*
Y-386855D01*
G01X847935D02*
Y-369355D01*
X843569D01*
X841822Y-370230D01*
X840512Y-371397D01*
X839420Y-373146D01*
X838547Y-375189D01*
X838329Y-378105D01*
X838547Y-381022D01*
X839420Y-383064D01*
X840512Y-384814D01*
X841822Y-385980D01*
X843569Y-386855D01*
X847935D01*
G01X830015Y-324355D02*
Y-341855D01*
X838749D01*
G01X855812D02*
Y-330189D01*
G01Y-332230D02*
X854939Y-331064D01*
X853628Y-330480D01*
X852100Y-330189D01*
X850572Y-330772D01*
X849262Y-331938D01*
X848388Y-333688D01*
X847952Y-336022D01*
X848388Y-338355D01*
X849262Y-340105D01*
X850572Y-341272D01*
X852100Y-341855D01*
X853628Y-341563D01*
X854939Y-340689D01*
X855812Y-339522D01*
G01X864797Y-347105D02*
X866107Y-347688D01*
X867854Y-347105D01*
X868945Y-345939D01*
X869819Y-344480D01*
X871128Y-339814D01*
X873967Y-330189D01*
G01X866980D02*
X871128Y-339814D01*
G01X883607Y-333980D02*
X890594D01*
X889939Y-331938D01*
X888847Y-330772D01*
X887319Y-330189D01*
X885790Y-330480D01*
X884480Y-331355D01*
X883607Y-333397D01*
X883170Y-335147D01*
Y-336897D01*
X883607Y-338647D01*
X884699Y-340397D01*
X886009Y-341563D01*
X887537Y-341855D01*
X889065Y-341272D01*
X890594Y-339522D01*
G01X901325Y-341855D02*
Y-330189D01*
G01Y-332522D02*
X902417Y-331355D01*
X903509Y-330480D01*
X905037Y-330189D01*
X906128Y-330480D01*
X907439Y-331355D01*
G01X994432Y-386855D02*
X992685Y-386563D01*
X991157Y-385397D01*
X989847Y-383647D01*
X988973Y-381605D01*
X988537Y-379272D01*
Y-376938D01*
X988973Y-374605D01*
X989847Y-372563D01*
X991157Y-370814D01*
X992685Y-369647D01*
X994432Y-369355D01*
X996178Y-369647D01*
X997707Y-370814D01*
X999017Y-372563D01*
X999891Y-374605D01*
X1000327Y-376938D01*
Y-379272D01*
X999891Y-381605D01*
X999017Y-383647D01*
X997707Y-385397D01*
X996178Y-386563D01*
X994432Y-386855D01*
G01X996178Y-382188D02*
X998799Y-386855D01*
G01X1007129Y-369355D02*
Y-381897D01*
X1008002Y-384522D01*
X1009749Y-386272D01*
X1011932Y-386855D01*
X1014115Y-386272D01*
X1015862Y-384522D01*
X1016735Y-381897D01*
Y-369355D01*
G01X1026812D02*
X1032052D01*
G01X1029432D02*
Y-386855D01*
G01X1026812D02*
X1032052D01*
G01X1041910D02*
Y-369355D01*
X1051954Y-386855D01*
Y-369355D01*
G01X1069235Y-370814D02*
X1067925Y-369938D01*
X1066397Y-369355D01*
X1064650D01*
X1062685Y-370230D01*
X1061157Y-371688D01*
X1060065Y-373439D01*
X1059192Y-376355D01*
X1058973Y-378980D01*
X1059410Y-381605D01*
X1060065Y-383355D01*
X1061375Y-385105D01*
X1062904Y-386272D01*
X1064432Y-386855D01*
X1065960D01*
X1067489Y-386272D01*
X1068799Y-385397D01*
X1069891Y-384231D01*
G01X1081932Y-386855D02*
Y-378980D01*
X1077565Y-369355D01*
G01X1086299D02*
X1081932Y-378980D01*
G01X972129Y-341855D02*
Y-324355D01*
X976495D01*
X978242Y-325230D01*
X979552Y-326397D01*
X980644Y-328146D01*
X981517Y-330189D01*
X981735Y-333105D01*
X981517Y-336022D01*
X980644Y-338064D01*
X979552Y-339814D01*
X978242Y-340980D01*
X976495Y-341855D01*
X972129D01*
G01X991157Y-333980D02*
X998144D01*
X997489Y-331938D01*
X996397Y-330772D01*
X994869Y-330189D01*
X993340Y-330480D01*
X992030Y-331355D01*
X991157Y-333397D01*
X990720Y-335147D01*
Y-336897D01*
X991157Y-338647D01*
X992249Y-340397D01*
X993559Y-341563D01*
X995087Y-341855D01*
X996615Y-341272D01*
X998144Y-339522D01*
G01X1008657Y-339814D02*
X1009749Y-340980D01*
X1011277Y-341855D01*
X1012587D01*
X1013897Y-341272D01*
X1014770Y-340397D01*
X1015207Y-339231D01*
X1014989Y-337480D01*
X1014115Y-336605D01*
X1010185Y-334855D01*
X1009312Y-332813D01*
X1009749Y-331355D01*
X1010622Y-330480D01*
X1011932Y-330189D01*
X1013242Y-330480D01*
X1014552Y-331355D01*
G01X1029432Y-330189D02*
Y-341855D01*
G01Y-325522D02*
X1028995Y-325230D01*
Y-324647D01*
X1029432Y-324355D01*
X1029869Y-324647D01*
Y-325230D01*
X1029432Y-325522D01*
G01X1043875Y-346230D02*
X1045404Y-347397D01*
X1047150Y-347688D01*
X1048678Y-347397D01*
X1049989Y-345939D01*
X1050862Y-343897D01*
Y-330189D01*
G01Y-332522D02*
X1049989Y-331355D01*
X1048678Y-330480D01*
X1047150Y-330189D01*
X1045404Y-330772D01*
X1044312Y-331938D01*
X1043438Y-333980D01*
X1043002Y-336022D01*
X1043220Y-337772D01*
X1044094Y-339814D01*
X1045404Y-341272D01*
X1047150Y-341855D01*
X1048460Y-341563D01*
X1049989Y-340397D01*
X1050862Y-339231D01*
G01X1060720Y-341855D02*
Y-330189D01*
G01Y-333105D02*
X1061594Y-331647D01*
X1062904Y-330480D01*
X1064650Y-330189D01*
X1066178Y-330480D01*
X1067489Y-331647D01*
X1068144Y-333688D01*
Y-341855D01*
G01X1078657Y-333980D02*
X1085644D01*
X1084989Y-331938D01*
X1083897Y-330772D01*
X1082369Y-330189D01*
X1080840Y-330480D01*
X1079530Y-331355D01*
X1078657Y-333397D01*
X1078220Y-335147D01*
Y-336897D01*
X1078657Y-338647D01*
X1079749Y-340397D01*
X1081059Y-341563D01*
X1082587Y-341855D01*
X1084115Y-341272D01*
X1085644Y-339522D01*
G01X1096375Y-341855D02*
Y-330189D01*
G01Y-332522D02*
X1097467Y-331355D01*
X1098559Y-330480D01*
X1100087Y-330189D01*
X1101178Y-330480D01*
X1102489Y-331355D01*
G01X1143132Y-369355D02*
X1141385Y-369938D01*
X1140075Y-371397D01*
X1139202Y-373146D01*
X1138547Y-375480D01*
X1138329Y-378105D01*
X1138547Y-380730D01*
X1139202Y-383064D01*
X1140075Y-384814D01*
X1141385Y-386272D01*
X1143132Y-386855D01*
X1144878Y-386272D01*
X1146189Y-384814D01*
X1147062Y-383064D01*
X1147717Y-380730D01*
X1147935Y-378105D01*
X1147717Y-375480D01*
X1147062Y-373146D01*
X1146189Y-371397D01*
X1144878Y-369938D01*
X1143132Y-369355D01*
G01X1156484Y-379564D02*
X1158012Y-377522D01*
X1159322Y-376355D01*
X1161069Y-375772D01*
X1162597Y-376355D01*
X1163689Y-377522D01*
X1164562Y-379272D01*
X1164780Y-381313D01*
X1164562Y-383064D01*
X1163689Y-384814D01*
X1162378Y-386272D01*
X1160850Y-386855D01*
X1159104Y-386272D01*
X1157575Y-384522D01*
X1156702Y-381897D01*
X1156484Y-378980D01*
X1156920Y-375189D01*
X1157575Y-373146D01*
X1158667Y-371105D01*
X1160195Y-369647D01*
X1161724Y-369355D01*
X1163252Y-369938D01*
X1164344Y-371397D01*
G01X1174202Y-387438D02*
X1182062Y-369355D01*
G01X1191484Y-372272D02*
X1192794Y-370522D01*
X1194322Y-369647D01*
X1196069Y-369355D01*
X1198252Y-369938D01*
X1199780Y-371397D01*
X1200217Y-373146D01*
X1199999Y-374897D01*
X1199125Y-376355D01*
X1194759Y-379272D01*
X1192794Y-381313D01*
X1191484Y-384231D01*
X1191047Y-386855D01*
X1200217D01*
G01X1213132D02*
Y-369355D01*
X1210512Y-372855D01*
G01Y-386855D02*
X1215752D01*
G01X1226702Y-387438D02*
X1234562Y-369355D01*
G01X1243984Y-372272D02*
X1245294Y-370522D01*
X1246822Y-369647D01*
X1248569Y-369355D01*
X1250752Y-369938D01*
X1252280Y-371397D01*
X1252717Y-373146D01*
X1252499Y-374897D01*
X1251625Y-376355D01*
X1247259Y-379272D01*
X1245294Y-381313D01*
X1243984Y-384231D01*
X1243547Y-386855D01*
X1252717D01*
G01X1265632Y-369355D02*
X1263885Y-369938D01*
X1262575Y-371397D01*
X1261702Y-373146D01*
X1261047Y-375480D01*
X1260829Y-378105D01*
X1261047Y-380730D01*
X1261702Y-383064D01*
X1262575Y-384814D01*
X1263885Y-386272D01*
X1265632Y-386855D01*
X1267378Y-386272D01*
X1268689Y-384814D01*
X1269562Y-383064D01*
X1270217Y-380730D01*
X1270435Y-378105D01*
X1270217Y-375480D01*
X1269562Y-373146D01*
X1268689Y-371397D01*
X1267378Y-369938D01*
X1265632Y-369355D01*
G01X1283132Y-386855D02*
Y-369355D01*
X1280512Y-372855D01*
G01Y-386855D02*
X1285752D01*
G01X1300195D02*
X1300632Y-383064D01*
X1301287Y-379855D01*
X1302160Y-376938D01*
X1303252Y-373730D01*
X1304999Y-369355D01*
X1296265D01*
G01X1190829Y-341855D02*
Y-324355D01*
X1195195D01*
X1196942Y-325230D01*
X1198252Y-326397D01*
X1199344Y-328146D01*
X1200217Y-330189D01*
X1200435Y-333105D01*
X1200217Y-336022D01*
X1199344Y-338064D01*
X1198252Y-339814D01*
X1196942Y-340980D01*
X1195195Y-341855D01*
X1190829D01*
G01X1217062D02*
Y-330189D01*
G01Y-332230D02*
X1216189Y-331064D01*
X1214878Y-330480D01*
X1213350Y-330189D01*
X1211822Y-330772D01*
X1210512Y-331938D01*
X1209638Y-333688D01*
X1209202Y-336022D01*
X1209638Y-338355D01*
X1210512Y-340105D01*
X1211822Y-341272D01*
X1213350Y-341855D01*
X1214878Y-341563D01*
X1216189Y-340689D01*
X1217062Y-339522D01*
G01X1230632Y-324355D02*
Y-341855D01*
G01X1227575Y-330189D02*
X1233689D01*
G01X1244857Y-333980D02*
X1251844D01*
X1251189Y-331938D01*
X1250097Y-330772D01*
X1248569Y-330189D01*
X1247040Y-330480D01*
X1245730Y-331355D01*
X1244857Y-333397D01*
X1244420Y-335147D01*
Y-336897D01*
X1244857Y-338647D01*
X1245949Y-340397D01*
X1247259Y-341563D01*
X1248787Y-341855D01*
X1250315Y-341272D01*
X1251844Y-339522D01*
G01X20103Y-86244D02*
G03I-4291J0D01*
G01X0Y-87362D02*
G03X15000Y-102362I15000J0D01*
G01X0Y-11811D02*
Y-87362D01*
G01X3937Y-7874D02*
G03X0Y-11811I0J-3937D01*
G01X15748Y-7874D02*
X3937D01*
G01X0Y7874D02*
G03X7874Y0I7874J0D01*
G01X818897D02*
X7874D01*
G01X0Y7874D02*
Y562992D01*
G01X7874Y570866D02*
G03X0Y562992I0J-7874D01*
G01X7874Y570866D02*
X326781D01*
G01X312004Y-102362D02*
X15000D01*
G01X46456Y0D02*
G03Y-7874I0J-3937D01*
G01X15748D02*
G03Y0I0J3937D01*
G01X287400Y-7874D02*
X46456D01*
G01X40452Y499724D02*
G03I-3051J0D01*
G01X41535Y535157D02*
G03I-4134J0D01*
G01X44685Y517441D02*
G03I-7284J0D01*
G01X121082Y39055D02*
G03I-5019J0D01*
G01X120807Y14567D02*
G03I-4744J0D01*
G01X319878Y-102362D02*
G03X312004I-3937J0D01*
G01X811771D02*
X319878D01*
G01X326770Y0D02*
G03Y-7874I0J-3937D01*
G01X287400D02*
G03Y0I0J3937D01*
G01X302165Y531496D02*
G03I-6890J0D01*
G01X597707Y-7874D02*
X326770D01*
G01X379921Y156220D02*
G03I-5906J0D01*
G01X342529Y530315D02*
G03X334655I-3937J0D01*
G01X342529Y520720D02*
G03X352474Y509057I11811J0D01*
G01X334655Y520720D02*
G03X351230Y501282I19685J0D01*
G01X384484Y503937D02*
X352475Y509057D01*
G01X383858Y496063D02*
X351231Y501282D01*
G01X442287Y503937D02*
X384484D01*
G01X442913Y496063D02*
X383858D01*
G01X342529Y530315D02*
Y520720D01*
G01X334655Y562992D02*
Y520720D01*
G01X346466Y570866D02*
G03X342529Y566929I0J-3937D01*
G01X334655Y555512D02*
G03X342529I3937J0D01*
G01X346466Y570866D02*
X480325D01*
G01X334655Y562992D02*
G03X326781Y570866I-7874J0D01*
G01X342529Y566929D02*
Y555512D01*
G01X415943Y539991D02*
G03I-4291J0D01*
G01X474316Y509060D02*
X442287Y503937D01*
G01X475560Y501285D02*
X442913Y496063D01*
G01X492136Y530315D02*
G03X484262I-3937J0D01*
G01X474316Y509060D02*
G03X484262Y520723I-1865J11663D01*
G01X475560Y501285D02*
G03X492136Y520723I-3109J19438D01*
G01X484262Y530315D02*
Y520723D01*
G01X492136Y562992D02*
Y520723D01*
G01X484262Y566929D02*
G03X480325Y570866I-3937J0D01*
G01X484262Y555512D02*
G03X492136I3937J0D01*
G01X500010Y570866D02*
G03X492136Y562992I0J-7874D01*
G01X500010Y570866D02*
X818897D01*
G01X484262Y566929D02*
Y555512D01*
G01X537401Y371299D02*
G03I-5905J0D01*
G01X538386Y531496D02*
G03I-6890J0D01*
G01X628416Y0D02*
G03Y-7874I0J-3937D01*
G01X597707D02*
G03Y0I0J3937D01*
G01X780315Y-7874D02*
X628416D01*
G01X602362Y116141D02*
G03I-5906J0D01*
G01X817003Y-86834D02*
G03I-4292J0D01*
G01X811771Y-102362D02*
G03X826771Y-87362I0J15000D01*
G01X811023Y0D02*
G03Y-7874I0J-3937D01*
G01X780315D02*
G03Y0I0J3937D01*
G01X822834Y-7874D02*
X811023D01*
G01X818897Y0D02*
G03X826771Y7874I0J7874D01*
G01X818897Y0D02*
X807086D01*
G01X787401Y198819D02*
G03I-5905J0D01*
G01X792421Y499724D02*
G03I-3051J0D01*
G01X793504Y535157D02*
G03I-4134J0D01*
G01X796653Y517441D02*
G03I-7283J0D01*
G01X826771Y562992D02*
G03X818897Y570866I-7874J0D01*
G01X826771Y-11811D02*
Y-87362D01*
G01Y-11811D02*
G03X822834Y-7874I-3937J0D01*
G01X826771Y562992D02*
Y7874D01*
G54D56*
X687500Y274750D03*
X683625Y282250D03*
X691375D03*
G54D47*
X366040Y320965D03*
X368600D03*
X371160D03*
Y329035D03*
X368600D03*
X366040D03*
G54D29*
X287500Y289700D03*
X358298Y253844D03*
X358342Y281987D03*
X358214Y310062D03*
X409100Y344000D03*
X421500Y344500D03*
X440740Y344644D03*
X435200Y334000D03*
X427500Y334100D03*
X421500Y334200D03*
X396000Y344100D03*
X467900Y354200D03*
X474577Y342865D03*
X496100Y355300D03*
X497206Y345231D03*
X464000Y344200D03*
X460000D03*
X451300Y344300D03*
X491445Y350358D03*
X477400Y354300D03*
X468000Y344200D03*
X486873Y350356D03*
X472000Y354200D03*
X482618Y342842D03*
X513517Y345246D03*
X521522D03*
X517517D03*
X518500Y355700D03*
X522500D03*
X549400Y489390D03*
X631500Y108700D03*
X632300Y158100D03*
X644710Y26267D03*
X637003Y65709D03*
X689468Y250105D03*
X691887Y267877D03*
X657031Y380083D03*
X666031D03*
X661531D03*
X698541Y202589D03*
X785350Y95200D03*
X781000D03*
X802696Y140800D03*
X786500D03*
X790500D03*
X796110Y186300D03*
X792000Y232700D03*
G54D38*
X367340Y250340D03*
Y253940D03*
X367368Y278487D03*
Y282087D03*
X367177Y306562D03*
Y310162D03*
X422323Y284048D03*
Y287648D03*
X418323Y284048D03*
Y287648D03*
X467534Y252200D03*
Y255800D03*
X467547Y259450D03*
Y263050D03*
X467537Y268396D03*
Y271996D03*
X775407Y123893D03*
Y127493D03*
G54D39*
X367368Y268041D03*
Y264441D03*
X369889Y296241D03*
Y292641D03*
X492132Y300373D03*
Y296773D03*
X469490Y295572D03*
Y291972D03*
X465640Y295572D03*
Y291972D03*
X651430Y174234D03*
Y170634D03*
X772000Y113300D03*
Y109700D03*
G54D48*
X425845Y231050D03*
X423645D03*
X425845Y233550D03*
X423645D03*
X396100Y226300D03*
X393900D03*
X396900Y230300D03*
X394700D03*
X435267Y273353D03*
X433067D03*
X428400Y257900D03*
X426200D03*
X419600Y254000D03*
X417400D03*
X428400D03*
X426200D03*
X409000Y250900D03*
X406800D03*
X436018Y257827D03*
X433818D03*
X504922Y230291D03*
X502722D03*
X504922Y218500D03*
X502722D03*
X504922Y226350D03*
X502722D03*
X504922Y222450D03*
X502722D03*
X504922Y214576D03*
X502722D03*
X504922Y234219D03*
X502722D03*
X483700Y285200D03*
X481500D03*
X490350Y242150D03*
X488150D03*
X483300Y238100D03*
X481100D03*
X483300Y273600D03*
X481100D03*
X483282Y265195D03*
X481082D03*
X483300Y269650D03*
X481100D03*
X490250Y281500D03*
X488050D03*
X490400Y257900D03*
X488200D03*
X483300Y249950D03*
X481100D03*
X483300Y281550D03*
X481100D03*
X490400Y246000D03*
X488200D03*
X508186Y289438D03*
X505986D03*
X490400Y261950D03*
X488200D03*
X490400Y253900D03*
X488200D03*
X483300Y246000D03*
X481100D03*
X507100Y262500D03*
X504900D03*
X483300Y257800D03*
X481100D03*
X483300Y277600D03*
X481100D03*
X483300Y242100D03*
X481100D03*
X490400Y250000D03*
X488200D03*
X483300Y253900D03*
X481100D03*
X490400Y269700D03*
X488200D03*
X491400Y289300D03*
X489200D03*
X483282Y262695D03*
X481082D03*
X499200Y309020D03*
X497000D03*
X542100Y291500D03*
X539900D03*
X542300Y287400D03*
X540100D03*
X542300Y285200D03*
X540100D03*
X542300Y281300D03*
X540100D03*
X542300Y279100D03*
X540100D03*
X542300Y275200D03*
X540100D03*
X542300Y273000D03*
X540100D03*
X542300Y269100D03*
X540100D03*
X542300Y266900D03*
X540100D03*
X542300Y263100D03*
X540100D03*
X542300Y260900D03*
X540100D03*
X530601Y256167D03*
X528401D03*
X530601Y253967D03*
X528401D03*
X537200Y297600D03*
X535000D03*
X537200Y299800D03*
X535000D03*
X542100Y293700D03*
X539900D03*
X514600Y310000D03*
X512400D03*
X537500Y317200D03*
X535300D03*
X537500Y319400D03*
X535300D03*
X537400Y311200D03*
X535200D03*
X537400Y313400D03*
X535200D03*
X537300Y305100D03*
X535100D03*
X537300Y307300D03*
X535100D03*
X651483Y111296D03*
X649283D03*
X651483Y108996D03*
X649283D03*
X685300Y162630D03*
X683100D03*
X678747Y171175D03*
X676547D03*
X678747Y168975D03*
X676547D03*
X685250Y168930D03*
X683050D03*
X685300Y164830D03*
X683100D03*
X685250Y171130D03*
X683050D03*
X692141Y189723D03*
X689941D03*
X684682Y195495D03*
X682482D03*
X686992Y189743D03*
X684792D03*
X722142Y170065D03*
X719942D03*
X723000Y164200D03*
X720800D03*
X722242Y157715D03*
X720042D03*
X722142Y151175D03*
X719942D03*
X722142Y145165D03*
X719942D03*
X723200Y139500D03*
X721000D03*
X723452Y132025D03*
X721252D03*
X702400Y125000D03*
X700200D03*
X707600D03*
X705400D03*
X713100D03*
X710900D03*
X718600D03*
X716400D03*
X707435Y189777D03*
X705235D03*
X722142Y189185D03*
X719942D03*
X722142Y182795D03*
X719942D03*
X722142Y176315D03*
X719942D03*
X701588Y189806D03*
X699388D03*
G54D57*
X673000Y282250D03*
X676875Y274750D03*
X669125D03*
X776000Y85750D03*
X779875Y78250D03*
X772125D03*
X799500Y100750D03*
X803375Y93250D03*
X795625D03*
G54D58*
X669700Y366779D03*
X680700D03*
G54D49*
X407500Y237100D03*
X411398Y231600D03*
Y229400D03*
X395500Y235300D03*
Y233100D03*
X420700Y227400D03*
Y225200D03*
X435600Y227400D03*
Y225200D03*
X430200Y227400D03*
Y225200D03*
X438100Y227400D03*
Y225200D03*
X438500Y235150D03*
Y232950D03*
X445900Y227400D03*
Y225200D03*
X431050Y235150D03*
Y232950D03*
X446400Y235150D03*
Y232950D03*
X427700Y227400D03*
Y225200D03*
X423200Y227400D03*
Y225200D03*
X443900Y235150D03*
Y232950D03*
X436000Y235150D03*
Y232950D03*
X428550Y235150D03*
Y232950D03*
X443400Y227400D03*
Y225200D03*
X412000Y265100D03*
Y262900D03*
X411436Y246100D03*
Y243900D03*
X414500Y265100D03*
Y262900D03*
X407500Y239300D03*
X443700Y284200D03*
Y282000D03*
X430300Y284600D03*
Y282400D03*
X446500Y284200D03*
Y282000D03*
X395500Y243200D03*
Y241000D03*
X435400Y284200D03*
Y282000D03*
X437900Y284200D03*
Y282000D03*
X427635Y241981D03*
Y239781D03*
X428000Y284600D03*
Y282400D03*
X445900Y262350D03*
Y260150D03*
X443500Y271400D03*
Y269200D03*
Y254950D03*
Y252750D03*
X443400Y262350D03*
Y260150D03*
X446000Y271400D03*
Y269200D03*
Y254950D03*
Y252750D03*
X415400Y314500D03*
Y312300D03*
X482750Y227400D03*
Y225200D03*
X462200Y235150D03*
Y232950D03*
X461650Y227400D03*
Y225200D03*
X454340Y235150D03*
Y232950D03*
X467600Y235150D03*
Y232950D03*
X459700Y235150D03*
Y232950D03*
X470100Y235150D03*
Y232950D03*
X496059Y205807D03*
Y203607D03*
X482402Y235178D03*
Y232978D03*
X475400Y235150D03*
Y232950D03*
X469550Y227400D03*
Y225200D03*
X474900Y227400D03*
Y225200D03*
X454150Y227400D03*
Y225200D03*
X459150Y227400D03*
Y225200D03*
X485250Y227400D03*
Y225200D03*
X477400Y227400D03*
Y225200D03*
X451650Y227400D03*
Y225200D03*
X477900Y235150D03*
Y232950D03*
X467050Y227400D03*
Y225200D03*
X451840Y235150D03*
Y232950D03*
X451200Y284100D03*
Y281900D03*
X478400Y285600D03*
Y283400D03*
X474520Y285600D03*
Y283400D03*
X470490Y284400D03*
Y282200D03*
X458100Y284100D03*
Y281900D03*
X465800Y284200D03*
Y282000D03*
X463300Y284200D03*
Y282000D03*
X455800Y284102D03*
Y281902D03*
X453500Y284100D03*
Y281900D03*
X459500Y271400D03*
Y269200D03*
X462000Y271400D03*
Y269200D03*
X451450Y254950D03*
Y252750D03*
X459450Y254950D03*
Y252750D03*
X454550Y262350D03*
Y260150D03*
X454000Y271400D03*
Y269200D03*
X459500Y262350D03*
Y260150D03*
X451500Y271400D03*
Y269200D03*
X453950Y254950D03*
Y252750D03*
X452050Y262350D03*
Y260150D03*
X461950Y254950D03*
Y252750D03*
X462000Y262350D03*
Y260150D03*
X649307Y82136D03*
Y79936D03*
X651807Y82136D03*
Y79936D03*
X656080Y82096D03*
Y79896D03*
X658580Y82096D03*
Y79896D03*
X665285Y83804D03*
Y81604D03*
X667550Y83794D03*
Y81594D03*
X672926Y83330D03*
Y81130D03*
X675326Y83330D03*
Y81130D03*
X681283Y83329D03*
Y81129D03*
X683563Y83330D03*
Y81130D03*
X689149Y83598D03*
Y81398D03*
X691382Y83599D03*
Y81399D03*
X696418Y141404D03*
Y139204D03*
X656875Y173552D03*
Y171352D03*
X683698Y141105D03*
Y138905D03*
X694192Y141403D03*
Y139203D03*
X687898Y141112D03*
Y138912D03*
X690100Y141100D03*
Y138900D03*
X663507Y189280D03*
Y187080D03*
X649027Y191577D03*
Y189377D03*
X656944Y179504D03*
Y177304D03*
X657045Y185173D03*
Y182973D03*
X721320Y128695D03*
Y126495D03*
G54D59*
X658500Y368650D03*
M02*
